FILE_TYPE = MACRO_DRAWING;
SET COLOR_WIRE YELLOW;
SET COLOR_PROP MONO;
SET COLOR_DOT WHITE;
SET COLOR_ARC YELLOW;
SET COLOR_BODY GREEN;
SET COLOR_NOTE MONO;
SET PROP_DISPLAY VALUE;
SET PAGE_NUMBER P158;
FORCEADD RES..1
(-2650 1525);
FORCEPROP 1 LAST MATERIAL EMPTY
J 0
(-2650 1375);
DISPLAY 0.617021 (-2650 1375);
PAINT RED (-2650 1375);
FORCEPROP 1 LAST WATTAGE 1/16W
J 2
(-2675 1375);
DISPLAY 0.617021 (-2675 1375);
PAINT SKYBLUE (-2675 1375);
FORCEPROP 1 LAST VALUE 0.0
J 2
(-2675 1425);
DISPLAY 0.617021 (-2675 1425);
PAINT SKYBLUE (-2675 1425);
FORCEPROP 1 LASTPIN (-2750 1525) $PN 1
J 0
(-2738 1537);
DISPLAY 0.617021 (-2738 1537);
PAINT ORANGE (-2738 1537);
FORCEPROP 1 LAST PACK_TYPE 0402
J 0
(-2400 1375);
DISPLAY 0.617021 (-2400 1375);
PAINT SKYBLUE (-2400 1375);
FORCEPROP 1 LAST PART_NUMBER G21497-005
J 0
(-2525 1450);
DISPLAY 0.617021 (-2525 1450);
PAINT BLUE (-2525 1450);
FORCEPROP 1 LAST TOLERANCE 5%
J 0
(-2650 1425);
DISPLAY 0.617021 (-2650 1425);
PAINT SKYBLUE (-2650 1425);
FORCEPROP 1 LASTPIN (-2550 1525) $PN 2
J 0
(-2588 1537);
DISPLAY 0.617021 (-2588 1537);
PAINT ORANGE (-2588 1537);
FORCEPROP 1 LAST LOCATION R9F24
J 0
(-2700 1625);
DISPLAY 0.617021 (-2700 1625);
PAINT AQUA (-2700 1625);
FORCEPROP 2 LAST CDS_LIB mstr_discrete
J 0
(-2650 1525);
PAINT ORANGE (-2650 1525);
DISPLAY INVISIBLE (-2650 1525);
FORCEPROP 2 LAST BOM_COST DEBUG
J 0
(-2700 1725);
DISPLAY 1.021277 (-2700 1725);
PAINT ORANGE (-2700 1725);
DISPLAY INVISIBLE (-2700 1725);
FORCEPROP 2 LAST SEC_TYPE 0402
J 0
(-2700 1725);
DISPLAY 1.021277 (-2700 1725);
PAINT ORANGE (-2700 1725);
DISPLAY INVISIBLE (-2700 1725);
FORCEPROP 2 LAST SEC 1
J 0
(-2700 1725);
DISPLAY 0.680851 (-2700 1725);
PAINT MONO (-2700 1725);
DISPLAY INVISIBLE (-2700 1725);
FORCEPROP 2 LAST CDS_LOCATION R9F24
J 0
(-2700 1625);
DISPLAY 0.617021 (-2700 1625);
PAINT AQUA (-2700 1625);
DISPLAY INVISIBLE (-2700 1625);
FORCEPROP 1 LAST PATH I100
J 0
(-2700 1675);
DISPLAY 0.978723 (-2700 1675);
PAINT WHITE (-2700 1675);
DISPLAY INVISIBLE (-2700 1675);
FORCEPROP 2 LAST ROOM UART_MUX
J 0
(-2700 1675);
DISPLAY 1.021277 (-2700 1675);
PAINT ORANGE (-2700 1675);
DISPLAY INVISIBLE (-2700 1675);
FORCEADD OFFPAGE..1
(-3950 2675);
FORCEPROP 2 LAST $XR2 190 
J 0
(-4442 2675);
DISPLAY 0.638298 (-4442 2675);
PAINT MONO (-4442 2675);
FORCEPROP 2 LAST $XR0 145 
J 0
(-4202 2675);
DISPLAY 0.638298 (-4202 2675);
PAINT MONO (-4202 2675);
FORCEPROP 2 LAST $XR1 183 
J 0
(-4322 2675);
DISPLAY 0.638298 (-4322 2675);
PAINT MONO (-4322 2675);
FORCEPROP 2 LAST PATH I124
J 0
(-4225 2725);
DISPLAY 1.021277 (-4225 2725);
PAINT ORANGE (-4225 2725);
DISPLAY INVISIBLE (-4225 2725);
FORCEPROP 1 LAST OFFPAGE TRUE
J 0
(-3625 2550);
DISPLAY 0.872340 (-3625 2550);
PAINT GREEN (-3625 2550);
DISPLAY INVISIBLE (-3625 2550);
FORCEPROP 2 LAST CDS_LIB mstr_standard
J 0
(-3950 2675);
PAINT ORANGE (-3950 2675);
DISPLAY INVISIBLE (-3950 2675);
FORCEPROP 1 LAST COMMENT_BODY TRUE
J 0
(-3825 2575);
DISPLAY 0.872340 (-3825 2575);
PAINT GREEN (-3825 2575);
DISPLAY INVISIBLE (-3825 2575);
FORCEADD OFFPAGE..1
(-3950 2575);
FORCEPROP 2 LAST $XR1 145 
J 0
(-4322 2575);
DISPLAY 0.638298 (-4322 2575);
PAINT MONO (-4322 2575);
FORCEPROP 2 LAST $XR0 119 
J 0
(-4202 2575);
DISPLAY 0.638298 (-4202 2575);
PAINT MONO (-4202 2575);
FORCEPROP 2 LAST PATH I125
J 0
(-4225 2625);
DISPLAY 1.021277 (-4225 2625);
PAINT ORANGE (-4225 2625);
DISPLAY INVISIBLE (-4225 2625);
FORCEPROP 1 LAST OFFPAGE TRUE
J 0
(-3625 2450);
DISPLAY 0.872340 (-3625 2450);
PAINT GREEN (-3625 2450);
DISPLAY INVISIBLE (-3625 2450);
FORCEPROP 1 LAST COMMENT_BODY TRUE
J 0
(-3825 2475);
DISPLAY 0.872340 (-3825 2475);
PAINT GREEN (-3825 2475);
DISPLAY INVISIBLE (-3825 2475);
FORCEPROP 2 LAST CDS_LIB mstr_standard
J 0
(-3950 2575);
PAINT ORANGE (-3950 2575);
DISPLAY INVISIBLE (-3950 2575);
FORCEADD OFFPAGE..1
(-3950 2625);
FORCEPROP 2 LAST $XR2 183 
J 0
(-4542 2625);
DISPLAY 0.638298 (-4542 2625);
PAINT MONO (-4542 2625);
FORCEPROP 2 LAST $XR3 190 
J 0
(-4442 2625);
DISPLAY 0.638298 (-4442 2625);
PAINT MONO (-4442 2625);
FORCEPROP 2 LAST $XR1 151 
J 0
(-4322 2625);
DISPLAY 0.638298 (-4322 2625);
PAINT MONO (-4322 2625);
FORCEPROP 2 LAST $XR0 145 
J 0
(-4202 2625);
DISPLAY 0.638298 (-4202 2625);
PAINT MONO (-4202 2625);
FORCEPROP 2 LAST PATH I126
J 0
(-4225 2675);
DISPLAY 1.021277 (-4225 2675);
PAINT ORANGE (-4225 2675);
DISPLAY INVISIBLE (-4225 2675);
FORCEPROP 1 LAST OFFPAGE TRUE
J 0
(-3625 2500);
DISPLAY 0.872340 (-3625 2500);
PAINT GREEN (-3625 2500);
DISPLAY INVISIBLE (-3625 2500);
FORCEPROP 1 LAST COMMENT_BODY TRUE
J 0
(-3825 2525);
DISPLAY 0.872340 (-3825 2525);
PAINT GREEN (-3825 2525);
DISPLAY INVISIBLE (-3825 2525);
FORCEPROP 2 LAST CDS_LIB mstr_standard
J 0
(-3950 2625);
PAINT ORANGE (-3950 2625);
DISPLAY INVISIBLE (-3950 2625);
FORCEADD OFFPAGE..2
(-725 850);
FORCEPROP 2 LAST $XR1 145 
J 0
(-416 850);
DISPLAY 0.638298 (-416 850);
PAINT MONO (-416 850);
FORCEPROP 2 LAST $XR0 119 
J 0
(-536 850);
DISPLAY 0.638298 (-536 850);
PAINT MONO (-536 850);
FORCEPROP 1 LAST COMMENT_BODY TRUE
J 0
(-770 755);
DISPLAY 0.872340 (-770 755);
PAINT GREEN (-770 755);
DISPLAY INVISIBLE (-770 755);
FORCEPROP 2 LAST CDS_LIB mstr_standard
J 0
(-725 850);
PAINT MONO (-725 850);
DISPLAY INVISIBLE (-725 850);
FORCEPROP 1 LAST OFFPAGE TRUE
J 0
(-400 725);
DISPLAY 0.872340 (-400 725);
PAINT GREEN (-400 725);
DISPLAY INVISIBLE (-400 725);
FORCEPROP 2 LAST PATH I127
J 0
(-275 900);
DISPLAY 1.021277 (-275 900);
PAINT ORANGE (-275 900);
DISPLAY INVISIBLE (-275 900);
FORCEADD OFFPAGE..2
(-725 950);
FORCEPROP 2 LAST $XR2 190 
J 0
(-296 950);
DISPLAY 0.638298 (-296 950);
PAINT MONO (-296 950);
FORCEPROP 2 LAST $XR0 145 
J 0
(-536 950);
DISPLAY 0.638298 (-536 950);
PAINT MONO (-536 950);
FORCEPROP 2 LAST $XR1 183 
J 0
(-416 950);
DISPLAY 0.638298 (-416 950);
PAINT MONO (-416 950);
FORCEPROP 1 LAST COMMENT_BODY TRUE
J 0
(-770 855);
DISPLAY 0.872340 (-770 855);
PAINT GREEN (-770 855);
DISPLAY INVISIBLE (-770 855);
FORCEPROP 2 LAST CDS_LIB mstr_standard
J 0
(-725 950);
PAINT MONO (-725 950);
DISPLAY INVISIBLE (-725 950);
FORCEPROP 1 LAST OFFPAGE TRUE
J 0
(-400 825);
DISPLAY 0.872340 (-400 825);
PAINT GREEN (-400 825);
DISPLAY INVISIBLE (-400 825);
FORCEPROP 2 LAST PATH I128
J 0
(-275 1000);
DISPLAY 1.021277 (-275 1000);
PAINT ORANGE (-275 1000);
DISPLAY INVISIBLE (-275 1000);
FORCEADD OFFPAGE..2
(-725 900);
FORCEPROP 2 LAST $XR0 145 
J 0
(-536 900);
DISPLAY 0.638298 (-536 900);
PAINT MONO (-536 900);
FORCEPROP 2 LAST $XR1 183 
J 0
(-416 900);
DISPLAY 0.638298 (-416 900);
PAINT MONO (-416 900);
FORCEPROP 2 LAST $XR2 190 
J 0
(-296 900);
DISPLAY 0.638298 (-296 900);
PAINT MONO (-296 900);
FORCEPROP 1 LAST COMMENT_BODY TRUE
J 0
(-770 805);
DISPLAY 0.872340 (-770 805);
PAINT GREEN (-770 805);
DISPLAY INVISIBLE (-770 805);
FORCEPROP 2 LAST CDS_LIB mstr_standard
J 0
(-725 900);
PAINT MONO (-725 900);
DISPLAY INVISIBLE (-725 900);
FORCEPROP 1 LAST OFFPAGE TRUE
J 0
(-400 775);
DISPLAY 0.872340 (-400 775);
PAINT GREEN (-400 775);
DISPLAY INVISIBLE (-400 775);
FORCEPROP 2 LAST PATH I129
J 0
(-275 950);
DISPLAY 1.021277 (-275 950);
PAINT ORANGE (-275 950);
DISPLAY INVISIBLE (-275 950);
FORCEADD LED..3
(-5725 3200);
FORCEPROP 1 LAST PART_NUMBER D14725-022
J 0
(-5825 3050);
DISPLAY 0.617021 (-5825 3050);
PAINT BLUE (-5825 3050);
FORCEPROP 1 LAST COLOR GREEN
J 0
(-5825 3300);
DISPLAY 0.617021 (-5825 3300);
PAINT BLUE (-5825 3300);
FORCEPROP 2 LASTPIN (-5825 3200) $PN 2
J 2
(-5835 3210);
DISPLAY 0.617021 (-5835 3210);
PAINT ORANGE (-5835 3210);
FORCEPROP 1 LAST MATERIAL IC
J 0
(-5825 3350);
DISPLAY 0.617021 (-5825 3350);
PAINT SKYBLUE (-5825 3350);
FORCEPROP 1 LAST LOCATION DS9A4
J 0
(-5825 3400);
DISPLAY 0.617021 (-5825 3400);
PAINT AQUA (-5825 3400);
FORCEPROP 2 LASTPIN (-5625 3200) $PN 1
J 0
(-5615 3210);
DISPLAY 0.617021 (-5615 3210);
PAINT ORANGE (-5615 3210);
FORCEPROP 2 LAST CDS_LIB mstr_discrete
J 0
(-5725 3200);
PAINT ORANGE (-5725 3200);
DISPLAY INVISIBLE (-5725 3200);
FORCEPROP 2 LAST BOM_COST DEBUG
J 0
(-5825 3500);
DISPLAY 1.021277 (-5825 3500);
PAINT ORANGE (-5825 3500);
DISPLAY INVISIBLE (-5825 3500);
FORCEPROP 2 LAST SEC_TYPE A1LF
J 0
(-5825 3450);
DISPLAY 1.021277 (-5825 3450);
PAINT ORANGE (-5825 3450);
DISPLAY INVISIBLE (-5825 3450);
FORCEPROP 2 LAST SEC 1
J 0
(-5825 3450);
DISPLAY 0.680851 (-5825 3450);
PAINT MONO (-5825 3450);
DISPLAY INVISIBLE (-5825 3450);
FORCEPROP 2 LAST CDS_LOCATION DS9A4
J 0
(-5825 3400);
DISPLAY 0.617021 (-5825 3400);
PAINT AQUA (-5825 3400);
DISPLAY INVISIBLE (-5825 3400);
FORCEPROP 2 LAST ROOM UART_MUX
J 0
(-5825 3450);
DISPLAY 1.021277 (-5825 3450);
PAINT ORANGE (-5825 3450);
DISPLAY INVISIBLE (-5825 3450);
FORCEPROP 1 LAST PACK_TYPE A1LF
J 0
(-5825 3450);
DISPLAY 0.978723 (-5825 3450);
PAINT SKYBLUE (-5825 3450);
DISPLAY INVISIBLE (-5825 3450);
FORCEPROP 1 LAST PATH I130
J 0
(-5375 3350);
DISPLAY 0.978723 (-5375 3350);
PAINT BLUE (-5375 3350);
DISPLAY INVISIBLE (-5375 3350);
FORCEADD RES..1
(-4875 3200);
FORCEPROP 1 LAST WATTAGE 1/16W
J 2
(-4900 3050);
DISPLAY 0.617021 (-4900 3050);
PAINT SKYBLUE (-4900 3050);
FORCEPROP 1 LAST PART_NUMBER G21497-028
J 0
(-4925 3300);
DISPLAY 0.617021 (-4925 3300);
PAINT BLUE (-4925 3300);
FORCEPROP 1 LAST PACK_TYPE 0402
J 0
(-4625 3050);
DISPLAY 0.617021 (-4625 3050);
PAINT SKYBLUE (-4625 3050);
FORCEPROP 1 LAST MATERIAL CHIP
J 0
(-4875 3050);
DISPLAY 0.617021 (-4875 3050);
PAINT SKYBLUE (-4875 3050);
FORCEPROP 1 LASTPIN (-4975 3200) $PN 1
J 0
(-4963 3212);
DISPLAY 0.617021 (-4963 3212);
PAINT ORANGE (-4963 3212);
FORCEPROP 1 LAST VALUE 330
J 2
(-4900 3100);
DISPLAY 0.617021 (-4900 3100);
PAINT SKYBLUE (-4900 3100);
FORCEPROP 1 LAST LOCATION R1L43
J 0
(-4925 3250);
DISPLAY 0.617021 (-4925 3250);
PAINT AQUA (-4925 3250);
FORCEPROP 1 LASTPIN (-4775 3200) $PN 2
J 0
(-4813 3212);
DISPLAY 0.617021 (-4813 3212);
PAINT ORANGE (-4813 3212);
FORCEPROP 1 LAST TOLERANCE 5%
J 0
(-4875 3100);
DISPLAY 0.617021 (-4875 3100);
PAINT SKYBLUE (-4875 3100);
FORCEPROP 2 LAST CDS_LIB mstr_discrete
J 0
(-4875 3200);
PAINT ORANGE (-4875 3200);
DISPLAY INVISIBLE (-4875 3200);
FORCEPROP 2 LAST CDS_LOCATION R1L43
J 0
(-4925 3250);
DISPLAY 0.617021 (-4925 3250);
PAINT AQUA (-4925 3250);
DISPLAY INVISIBLE (-4925 3250);
FORCEPROP 1 LAST PATH I131
J 0
(-4925 3350);
DISPLAY 0.978723 (-4925 3350);
PAINT WHITE (-4925 3350);
DISPLAY INVISIBLE (-4925 3350);
FORCEPROP 2 LAST SEC 1
J 0
(-4925 3400);
DISPLAY 0.680851 (-4925 3400);
PAINT MONO (-4925 3400);
DISPLAY INVISIBLE (-4925 3400);
FORCEPROP 2 LAST BOM_COST DEBUG
J 0
(-4925 3400);
DISPLAY 1.021277 (-4925 3400);
PAINT ORANGE (-4925 3400);
DISPLAY INVISIBLE (-4925 3400);
FORCEPROP 2 LAST SEC_TYPE 0402
J 0
(-4925 3400);
DISPLAY 1.021277 (-4925 3400);
PAINT ORANGE (-4925 3400);
DISPLAY INVISIBLE (-4925 3400);
FORCEPROP 2 LAST ROOM UART_MUX
J 0
(-4925 3350);
DISPLAY 1.021277 (-4925 3350);
PAINT ORANGE (-4925 3350);
DISPLAY INVISIBLE (-4925 3350);
FORCEADD OFFPAGE..1
(-7100 3200);
FORCEPROP 2 LAST $XR0 147 
J 0
(-7352 3200);
DISPLAY 0.638298 (-7352 3200);
PAINT MONO (-7352 3200);
FORCEPROP 2 LAST $XR1 190 
J 0
(-7472 3200);
DISPLAY 0.638298 (-7472 3200);
PAINT MONO (-7472 3200);
FORCEPROP 2 LAST $XR2 120 
J 0
(-7592 3200);
DISPLAY 0.638298 (-7592 3200);
PAINT MONO (-7592 3200);
FORCEPROP 2 LAST $XR3 158 
J 0
(-7712 3200);
DISPLAY 0.638298 (-7712 3200);
PAINT MONO (-7712 3200);
FORCEPROP 2 LAST CDS_LIB mstr_standard
J 0
(-7100 3200);
PAINT ORANGE (-7100 3200);
DISPLAY INVISIBLE (-7100 3200);
FORCEPROP 1 LAST COMMENT_BODY TRUE
J 0
(-6975 3100);
DISPLAY 0.872340 (-6975 3100);
PAINT GREEN (-6975 3100);
DISPLAY INVISIBLE (-6975 3100);
FORCEPROP 2 LAST PATH I132
J 0
(-7050 3275);
DISPLAY 1.021277 (-7050 3275);
PAINT ORANGE (-7050 3275);
DISPLAY INVISIBLE (-7050 3275);
FORCEPROP 1 LAST OFFPAGE TRUE
J 0
(-6775 3075);
DISPLAY 0.872340 (-6775 3075);
PAINT GREEN (-6775 3075);
DISPLAY INVISIBLE (-6775 3075);
FORCEADD LED..3
(-5725 3600);
FORCEPROP 1 LAST COLOR GREEN
J 0
(-5825 3700);
DISPLAY 0.617021 (-5825 3700);
PAINT BLUE (-5825 3700);
FORCEPROP 2 LASTPIN (-5825 3600) $PN 2
J 2
(-5835 3610);
DISPLAY 0.617021 (-5835 3610);
PAINT ORANGE (-5835 3610);
FORCEPROP 1 LAST MATERIAL IC
J 0
(-5825 3750);
DISPLAY 0.617021 (-5825 3750);
PAINT SKYBLUE (-5825 3750);
FORCEPROP 1 LAST LOCATION DS9A7
J 0
(-5825 3800);
DISPLAY 0.617021 (-5825 3800);
PAINT AQUA (-5825 3800);
FORCEPROP 1 LAST PART_NUMBER D14725-022
J 0
(-5825 3450);
DISPLAY 0.617021 (-5825 3450);
PAINT BLUE (-5825 3450);
FORCEPROP 2 LASTPIN (-5625 3600) $PN 1
J 0
(-5615 3610);
DISPLAY 0.617021 (-5615 3610);
PAINT ORANGE (-5615 3610);
FORCEPROP 2 LAST CDS_LIB mstr_discrete
J 0
(-5725 3600);
PAINT ORANGE (-5725 3600);
DISPLAY INVISIBLE (-5725 3600);
FORCEPROP 2 LAST CDS_LOCATION DS9A7
J 0
(-5825 3800);
DISPLAY 0.617021 (-5825 3800);
PAINT AQUA (-5825 3800);
DISPLAY INVISIBLE (-5825 3800);
FORCEPROP 2 LAST BOM_COST DEBUG
J 0
(-5825 3900);
DISPLAY 1.021277 (-5825 3900);
PAINT ORANGE (-5825 3900);
DISPLAY INVISIBLE (-5825 3900);
FORCEPROP 2 LAST SEC_TYPE A1LF
J 0
(-5825 3850);
DISPLAY 1.021277 (-5825 3850);
PAINT ORANGE (-5825 3850);
DISPLAY INVISIBLE (-5825 3850);
FORCEPROP 2 LAST SEC 1
J 0
(-5825 3850);
DISPLAY 0.680851 (-5825 3850);
PAINT MONO (-5825 3850);
DISPLAY INVISIBLE (-5825 3850);
FORCEPROP 2 LAST ROOM UART_MUX
J 0
(-5825 3850);
DISPLAY 1.021277 (-5825 3850);
PAINT ORANGE (-5825 3850);
DISPLAY INVISIBLE (-5825 3850);
FORCEPROP 1 LAST PACK_TYPE A1LF
J 0
(-5825 3850);
DISPLAY 0.978723 (-5825 3850);
PAINT SKYBLUE (-5825 3850);
DISPLAY INVISIBLE (-5825 3850);
FORCEPROP 1 LAST PATH I134
J 0
(-5375 3750);
DISPLAY 0.978723 (-5375 3750);
PAINT BLUE (-5375 3750);
DISPLAY INVISIBLE (-5375 3750);
FORCEADD P3V3_STBY..1
(-4400 3850);
FORCEPROP 3 LASTPIN (-4400 3800) SIG_NAME P3V3_STBY\g
J 0
(-4390 3810);
DISPLAY 0.659574 (-4390 3810);
PAINT MONO (-4390 3810);
DISPLAY INVISIBLE (-4390 3810);
FORCEPROP 1 LAST HDL_POWER P3V3_STBY
J 0
(-4700 3725);
DISPLAY 0.872340 (-4700 3725);
PAINT ORANGE (-4700 3725);
DISPLAY INVISIBLE (-4700 3725);
FORCEPROP 1 LAST VOLTAGE 3.3V
J 0
(-4445 3807);
DISPLAY 0.340426 (-4445 3807);
PAINT SKYBLUE (-4445 3807);
DISPLAY INVISIBLE (-4445 3807);
FORCEPROP 1 LAST BODY_TYPE PLUMBING
J 0
(-4445 3807);
DISPLAY 0.340426 (-4445 3807);
PAINT GREEN (-4445 3807);
DISPLAY INVISIBLE (-4445 3807);
FORCEPROP 1 LAST PATH I135
J 0
(-4355 3852);
DISPLAY 0.340426 (-4355 3852);
PAINT GREEN (-4355 3852);
DISPLAY INVISIBLE (-4355 3852);
FORCEPROP 2 LAST CDS_LIB mstr_symbols
J 0
(-4400 3850);
PAINT ORANGE (-4400 3850);
DISPLAY INVISIBLE (-4400 3850);
FORCEPROP 1 LAST SIZE 1B
J 0
(-4355 3872);
DISPLAY 0.340426 (-4355 3872);
PAINT GREEN (-4355 3872);
DISPLAY INVISIBLE (-4355 3872);
FORCEADD RES..1
(-4875 3600);
FORCEPROP 1 LAST PART_NUMBER G21497-028
J 0
(-4925 3700);
DISPLAY 0.617021 (-4925 3700);
PAINT BLUE (-4925 3700);
FORCEPROP 1 LAST WATTAGE 1/16W
J 2
(-4900 3450);
DISPLAY 0.617021 (-4900 3450);
PAINT SKYBLUE (-4900 3450);
FORCEPROP 1 LAST VALUE 330
J 2
(-4900 3500);
DISPLAY 0.617021 (-4900 3500);
PAINT SKYBLUE (-4900 3500);
FORCEPROP 1 LAST MATERIAL CHIP
J 0
(-4875 3450);
DISPLAY 0.617021 (-4875 3450);
PAINT SKYBLUE (-4875 3450);
FORCEPROP 1 LASTPIN (-4975 3600) $PN 1
J 0
(-4963 3612);
DISPLAY 0.617021 (-4963 3612);
PAINT ORANGE (-4963 3612);
FORCEPROP 1 LAST LOCATION R1L44
J 0
(-4925 3650);
DISPLAY 0.617021 (-4925 3650);
PAINT AQUA (-4925 3650);
FORCEPROP 1 LASTPIN (-4775 3600) $PN 2
J 0
(-4813 3612);
DISPLAY 0.617021 (-4813 3612);
PAINT ORANGE (-4813 3612);
FORCEPROP 1 LAST PACK_TYPE 0402
J 0
(-4625 3450);
DISPLAY 0.617021 (-4625 3450);
PAINT SKYBLUE (-4625 3450);
FORCEPROP 1 LAST TOLERANCE 5%
J 0
(-4875 3500);
DISPLAY 0.617021 (-4875 3500);
PAINT SKYBLUE (-4875 3500);
FORCEPROP 2 LAST SEC 1
J 0
(-4925 3800);
DISPLAY 0.680851 (-4925 3800);
PAINT MONO (-4925 3800);
DISPLAY INVISIBLE (-4925 3800);
FORCEPROP 2 LAST CDS_LIB mstr_discrete
J 0
(-4875 3600);
PAINT ORANGE (-4875 3600);
DISPLAY INVISIBLE (-4875 3600);
FORCEPROP 2 LAST SEC_TYPE 0402
J 0
(-4925 3800);
DISPLAY 1.021277 (-4925 3800);
PAINT ORANGE (-4925 3800);
DISPLAY INVISIBLE (-4925 3800);
FORCEPROP 1 LAST PATH I136
J 0
(-4925 3750);
DISPLAY 0.978723 (-4925 3750);
PAINT WHITE (-4925 3750);
DISPLAY INVISIBLE (-4925 3750);
FORCEPROP 2 LAST CDS_LOCATION R1L44
J 0
(-4925 3650);
DISPLAY 0.617021 (-4925 3650);
PAINT AQUA (-4925 3650);
DISPLAY INVISIBLE (-4925 3650);
FORCEPROP 2 LAST BOM_COST DEBUG
J 0
(-4925 3800);
DISPLAY 1.021277 (-4925 3800);
PAINT ORANGE (-4925 3800);
DISPLAY INVISIBLE (-4925 3800);
FORCEPROP 2 LAST ROOM UART_MUX
J 0
(-4925 3750);
DISPLAY 1.021277 (-4925 3750);
PAINT ORANGE (-4925 3750);
DISPLAY INVISIBLE (-4925 3750);
FORCEADD OFFPAGE..1
(-7100 3600);
FORCEPROP 2 LAST $XR0 147 
J 0
(-7352 3600);
DISPLAY 0.638298 (-7352 3600);
PAINT MONO (-7352 3600);
FORCEPROP 2 LAST $XR1 190 
J 0
(-7472 3600);
DISPLAY 0.638298 (-7472 3600);
PAINT MONO (-7472 3600);
FORCEPROP 2 LAST $XR2 120 
J 0
(-7592 3600);
DISPLAY 0.638298 (-7592 3600);
PAINT MONO (-7592 3600);
FORCEPROP 2 LAST $XR3 158 
J 0
(-7712 3600);
DISPLAY 0.638298 (-7712 3600);
PAINT MONO (-7712 3600);
FORCEPROP 1 LAST COMMENT_BODY TRUE
J 0
(-6975 3500);
DISPLAY 0.872340 (-6975 3500);
PAINT GREEN (-6975 3500);
DISPLAY INVISIBLE (-6975 3500);
FORCEPROP 1 LAST OFFPAGE TRUE
J 0
(-6775 3475);
DISPLAY 0.872340 (-6775 3475);
PAINT GREEN (-6775 3475);
DISPLAY INVISIBLE (-6775 3475);
FORCEPROP 2 LAST PATH I137
J 0
(-7050 3675);
DISPLAY 1.021277 (-7050 3675);
PAINT ORANGE (-7050 3675);
DISPLAY INVISIBLE (-7050 3675);
FORCEPROP 2 LAST CDS_LIB mstr_standard
J 0
(-7100 3600);
PAINT ORANGE (-7100 3600);
DISPLAY INVISIBLE (-7100 3600);
FORCEADD OFFPAGE..1
(-3925 3750);
FORCEPROP 2 LAST $XR0 181 
J 0
(-4177 3750);
DISPLAY 0.638298 (-4177 3750);
PAINT MONO (-4177 3750);
FORCEPROP 2 LAST CDS_LIB mstr_standard
J 0
(-3925 3750);
PAINT ORANGE (-3925 3750);
DISPLAY INVISIBLE (-3925 3750);
FORCEPROP 1 LAST COMMENT_BODY TRUE
J 0
(-3800 3650);
DISPLAY 0.872340 (-3800 3650);
PAINT GREEN (-3800 3650);
DISPLAY INVISIBLE (-3800 3650);
FORCEPROP 1 LAST OFFPAGE TRUE
J 0
(-3600 3625);
DISPLAY 0.872340 (-3600 3625);
PAINT GREEN (-3600 3625);
DISPLAY INVISIBLE (-3600 3625);
FORCEPROP 2 LAST PATH I144
J 0
(-3750 3825);
DISPLAY 1.021277 (-3750 3825);
PAINT ORANGE (-3750 3825);
DISPLAY INVISIBLE (-3750 3825);
FORCEADD OFFPAGE..2
(-475 1775);
FORCEPROP 2 LAST $XR0 181 
J 0
(-286 1775);
DISPLAY 0.638298 (-286 1775);
PAINT MONO (-286 1775);
FORCEPROP 1 LAST COMMENT_BODY TRUE
J 0
(-520 1680);
DISPLAY 0.872340 (-520 1680);
PAINT GREEN (-520 1680);
DISPLAY INVISIBLE (-520 1680);
FORCEPROP 2 LAST CDS_LIB mstr_standard
J 0
(-475 1775);
PAINT ORANGE (-475 1775);
DISPLAY INVISIBLE (-475 1775);
FORCEPROP 2 LAST PATH I147
J 0
(-300 1850);
DISPLAY 1.021277 (-300 1850);
PAINT ORANGE (-300 1850);
DISPLAY INVISIBLE (-300 1850);
FORCEPROP 1 LAST OFFPAGE TRUE
J 0
(-150 1650);
DISPLAY 0.872340 (-150 1650);
PAINT GREEN (-150 1650);
DISPLAY INVISIBLE (-150 1650);
FORCEADD RES..1
(-3125 3750);
FORCEPROP 1 LAST PACK_TYPE 0402
J 0
(-2875 3700);
DISPLAY 0.617021 (-2875 3700);
PAINT SKYBLUE (-2875 3700);
FORCEPROP 1 LAST MATERIAL CHIP
J 0
(-2975 3700);
DISPLAY 0.617021 (-2975 3700);
PAINT SKYBLUE (-2975 3700);
FORCEPROP 1 LAST TOLERANCE 5%
J 0
(-3050 3700);
DISPLAY 0.617021 (-3050 3700);
PAINT SKYBLUE (-3050 3700);
FORCEPROP 1 LAST WATTAGE 1/16W
J 2
(-3225 3700);
DISPLAY 0.617021 (-3225 3700);
PAINT SKYBLUE (-3225 3700);
FORCEPROP 1 LAST LOCATION R9F65
J 0
(-3175 3800);
DISPLAY 0.617021 (-3175 3800);
PAINT AQUA (-3175 3800);
FORCEPROP 1 LAST VALUE 0.0
J 2
(-3150 3700);
DISPLAY 0.617021 (-3150 3700);
PAINT SKYBLUE (-3150 3700);
FORCEPROP 1 LAST PART_NUMBER G21497-005
J 0
(-3275 3625);
DISPLAY 0.617021 (-3275 3625);
PAINT BLUE (-3275 3625);
FORCEPROP 2 LAST CDS_LIB mstr_discrete
J 0
(-3125 3750);
PAINT MONO (-3125 3750);
DISPLAY INVISIBLE (-3125 3750);
FORCEPROP 1 LAST PATH I148
J 0
(-3175 3900);
DISPLAY 0.978723 (-3175 3900);
PAINT WHITE (-3175 3900);
DISPLAY INVISIBLE (-3175 3900);
FORCEPROP 2 LAST BOM_COST DEBUG
J 0
(-3125 3900);
DISPLAY 1.021277 (-3125 3900);
PAINT ORANGE (-3125 3900);
DISPLAY INVISIBLE (-3125 3900);
FORCEPROP 2 LAST ROOM UART_MUX
J 0
(-3125 3850);
DISPLAY 1.021277 (-3125 3850);
PAINT ORANGE (-3125 3850);
DISPLAY INVISIBLE (-3125 3850);
FORCEPROP 1 LASTPIN (-3225 3750) $PN 1
J 0
(-3213 3762);
DISPLAY 0.787234 (-3213 3762);
PAINT ORANGE (-3213 3762);
DISPLAY INVISIBLE (-3213 3762);
FORCEPROP 1 LASTPIN (-3025 3750) $PN 2
J 0
(-3063 3762);
DISPLAY 0.787234 (-3063 3762);
PAINT ORANGE (-3063 3762);
DISPLAY INVISIBLE (-3063 3762);
FORCEADD RES..1
(-1400 850);
FORCEPROP 1 LAST PACK_TYPE 0402
J 0
(-1100 800);
DISPLAY 0.617021 (-1100 800);
PAINT SKYBLUE (-1100 800);
FORCEPROP 1 LAST MATERIAL EMPTY
J 0
(-1250 800);
DISPLAY 0.617021 (-1250 800);
PAINT RED (-1250 800);
FORCEPROP 1 LAST TOLERANCE 5%
J 0
(-975 800);
DISPLAY 0.617021 (-975 800);
PAINT SKYBLUE (-975 800);
FORCEPROP 1 LAST VALUE 0.0
J 2
(-1425 800);
DISPLAY 0.617021 (-1425 800);
PAINT SKYBLUE (-1425 800);
FORCEPROP 1 LAST WATTAGE 1/16W
J 2
(-1525 800);
DISPLAY 0.617021 (-1525 800);
PAINT SKYBLUE (-1525 800);
FORCEPROP 1 LAST LOCATION R9F68
J 0
(-1475 950);
DISPLAY 0.617021 (-1475 950);
PAINT AQUA (-1475 950);
FORCEPROP 1 LAST PART_NUMBER G21497-005
J 0
(-1550 675);
DISPLAY 0.617021 (-1550 675);
PAINT BLUE (-1550 675);
FORCEPROP 2 LAST ROOM UART_MUX
J 0
(-1400 950);
DISPLAY 1.021277 (-1400 950);
PAINT ORANGE (-1400 950);
DISPLAY INVISIBLE (-1400 950);
FORCEPROP 2 LAST BOM_COST DEBUG
J 0
(-1400 1000);
DISPLAY 1.021277 (-1400 1000);
PAINT ORANGE (-1400 1000);
DISPLAY INVISIBLE (-1400 1000);
FORCEPROP 2 LAST CDS_LIB mstr_discrete
J 0
(-1400 850);
PAINT ORANGE (-1400 850);
DISPLAY INVISIBLE (-1400 850);
FORCEPROP 1 LASTPIN (-1300 850) $PN 2
J 0
(-1338 862);
DISPLAY 0.787234 (-1338 862);
PAINT ORANGE (-1338 862);
DISPLAY INVISIBLE (-1338 862);
FORCEPROP 1 LASTPIN (-1500 850) $PN 1
J 0
(-1488 862);
DISPLAY 0.787234 (-1488 862);
PAINT ORANGE (-1488 862);
DISPLAY INVISIBLE (-1488 862);
FORCEPROP 0 LAST $SEC 1
J 0
(-1475 1000);
PAINT MONO (-1475 1000);
DISPLAY INVISIBLE (-1475 1000);
FORCEPROP 0 LAST CDS_SEC 1
J 0
(-1475 1000);
PAINT MONO (-1475 1000);
DISPLAY INVISIBLE (-1475 1000);
FORCEPROP 1 LAST PATH I149
J 0
(-1450 1000);
DISPLAY 0.978723 (-1450 1000);
PAINT WHITE (-1450 1000);
DISPLAY INVISIBLE (-1450 1000);
FORCEPROP 0 LAST CDS_LOCATION R9F68
J 0
(-1475 1000);
PAINT MONO (-1475 1000);
DISPLAY INVISIBLE (-1475 1000);
FORCEADD RES..1
(-1250 1775);
FORCEPROP 1 LAST WATTAGE 1/16W
J 2
(-1350 1725);
DISPLAY 0.617021 (-1350 1725);
PAINT SKYBLUE (-1350 1725);
FORCEPROP 1 LASTPIN (-1350 1775) $PN 1
J 0
(-1338 1787);
DISPLAY 0.617021 (-1338 1787);
PAINT ORANGE (-1338 1787);
FORCEPROP 1 LASTPIN (-1150 1775) $PN 2
J 0
(-1188 1787);
DISPLAY 0.617021 (-1188 1787);
PAINT ORANGE (-1188 1787);
FORCEPROP 1 LAST TOLERANCE 5%
J 0
(-1175 1725);
DISPLAY 0.617021 (-1175 1725);
PAINT SKYBLUE (-1175 1725);
FORCEPROP 1 LAST PACK_TYPE 0402
J 0
(-1000 1725);
DISPLAY 0.617021 (-1000 1725);
PAINT SKYBLUE (-1000 1725);
FORCEPROP 1 LAST MATERIAL CHIP
J 0
(-1100 1725);
DISPLAY 0.617021 (-1100 1725);
PAINT SKYBLUE (-1100 1725);
FORCEPROP 1 LAST VALUE 0.0
J 2
(-1275 1725);
DISPLAY 0.617021 (-1275 1725);
PAINT SKYBLUE (-1275 1725);
FORCEPROP 1 LAST LOCATION R9F69
J 0
(-1300 1825);
DISPLAY 0.617021 (-1300 1825);
PAINT AQUA (-1300 1825);
FORCEPROP 1 LAST PART_NUMBER G21497-005
J 0
(-1400 1650);
DISPLAY 0.617021 (-1400 1650);
PAINT BLUE (-1400 1650);
FORCEPROP 0 LAST CDS_SEC 1
J 0
(-1300 1875);
PAINT MONO (-1300 1875);
DISPLAY INVISIBLE (-1300 1875);
FORCEPROP 2 LAST CDS_LIB mstr_discrete
J 0
(-1250 1775);
PAINT ORANGE (-1250 1775);
DISPLAY INVISIBLE (-1250 1775);
FORCEPROP 2 LAST ROOM UART_MUX
J 0
(-1250 1875);
DISPLAY 1.021277 (-1250 1875);
PAINT ORANGE (-1250 1875);
DISPLAY INVISIBLE (-1250 1875);
FORCEPROP 2 LAST BOM_COST DEBUG
J 0
(-1250 1925);
DISPLAY 1.021277 (-1250 1925);
PAINT ORANGE (-1250 1925);
DISPLAY INVISIBLE (-1250 1925);
FORCEPROP 2 LAST SEC_TYPE 0402
J 0
(-1300 1975);
DISPLAY 1.021277 (-1300 1975);
PAINT ORANGE (-1300 1975);
DISPLAY INVISIBLE (-1300 1975);
FORCEPROP 2 LAST SEC 1
J 0
(-1300 1975);
DISPLAY 0.680851 (-1300 1975);
PAINT MONO (-1300 1975);
DISPLAY INVISIBLE (-1300 1975);
FORCEPROP 1 LAST PATH I150
J 0
(-1300 1925);
DISPLAY 0.978723 (-1300 1925);
PAINT WHITE (-1300 1925);
DISPLAY INVISIBLE (-1300 1925);
FORCEPROP 0 LAST CDS_LOCATION R9F69
J 0
(-1300 1875);
PAINT MONO (-1300 1875);
DISPLAY INVISIBLE (-1300 1875);
FORCEADD RES..1
(-3150 2575);
FORCEPROP 1 LAST PART_NUMBER G21497-005
J 0
(-3250 2375);
DISPLAY 0.617021 (-3250 2375);
PAINT BLUE (-3250 2375);
FORCEPROP 1 LAST MATERIAL EMPTY
J 0
(-3150 2425);
DISPLAY 0.617021 (-3150 2425);
PAINT RED (-3150 2425);
FORCEPROP 1 LAST PACK_TYPE 0402
J 0
(-2900 2425);
DISPLAY 0.617021 (-2900 2425);
PAINT SKYBLUE (-2900 2425);
FORCEPROP 1 LAST WATTAGE 1/16W
J 2
(-3175 2425);
DISPLAY 0.617021 (-3175 2425);
PAINT SKYBLUE (-3175 2425);
FORCEPROP 1 LAST VALUE 0.0
J 2
(-3175 2475);
DISPLAY 0.617021 (-3175 2475);
PAINT SKYBLUE (-3175 2475);
FORCEPROP 1 LAST TOLERANCE 5%
J 0
(-3150 2475);
DISPLAY 0.617021 (-3150 2475);
PAINT SKYBLUE (-3150 2475);
FORCEPROP 1 LAST LOCATION R9F66
J 0
(-3200 2625);
DISPLAY 0.617021 (-3200 2625);
PAINT AQUA (-3200 2625);
FORCEPROP 2 LAST ROOM UART_MUX
J 0
(-3200 2675);
DISPLAY 1.021277 (-3200 2675);
PAINT ORANGE (-3200 2675);
DISPLAY INVISIBLE (-3200 2675);
FORCEPROP 2 LAST BOM_COST DEBUG
J 0
(-3200 2725);
DISPLAY 1.021277 (-3200 2725);
PAINT ORANGE (-3200 2725);
DISPLAY INVISIBLE (-3200 2725);
FORCEPROP 1 LAST PATH I152
J 0
(-3200 2725);
DISPLAY 0.978723 (-3200 2725);
PAINT WHITE (-3200 2725);
DISPLAY INVISIBLE (-3200 2725);
FORCEPROP 2 LAST CDS_LIB mstr_discrete
J 0
(-3150 2575);
PAINT MONO (-3150 2575);
DISPLAY INVISIBLE (-3150 2575);
FORCEPROP 1 LASTPIN (-3250 2575) $PN 1
J 0
(-3238 2587);
DISPLAY 0.787234 (-3238 2587);
PAINT ORANGE (-3238 2587);
DISPLAY INVISIBLE (-3238 2587);
FORCEPROP 1 LASTPIN (-3050 2575) $PN 2
J 0
(-3088 2587);
DISPLAY 0.787234 (-3088 2587);
PAINT ORANGE (-3088 2587);
DISPLAY INVISIBLE (-3088 2587);
FORCEADD CAP_A..1
(-1775 2950);
FORCEPROP 1 LAST PART_NUMBER A36096-030
J 0
(-1725 2800);
DISPLAY 0.617021 (-1725 2800);
PAINT BLUE (-1725 2800);
FORCEPROP 1 LAST PACK_TYPE 0402V
J 0
(-1725 2750);
DISPLAY 0.617021 (-1725 2750);
PAINT SKYBLUE (-1725 2750);
FORCEPROP 1 LASTPIN (-1775 3050) $PN 1
J 0
(-1765 3030);
DISPLAY 0.617021 (-1765 3030);
PAINT ORANGE (-1765 3030);
FORCEPROP 1 LASTPIN (-1775 2850) $PN 2
J 0
(-1765 2830);
DISPLAY 0.617021 (-1765 2830);
PAINT ORANGE (-1765 2830);
FORCEPROP 1 LAST MATERIAL X7R
J 0
(-1725 2850);
DISPLAY 0.617021 (-1725 2850);
PAINT SKYBLUE (-1725 2850);
FORCEPROP 1 LAST VOLTAGE 16V
J 0
(-1725 2950);
DISPLAY 0.617021 (-1725 2950);
PAINT SKYBLUE (-1725 2950);
FORCEPROP 1 LAST TOLERANCE 10%
J 0
(-1725 2900);
DISPLAY 0.617021 (-1725 2900);
PAINT SKYBLUE (-1725 2900);
FORCEPROP 1 LAST VALUE 0.1UF
J 0
(-1725 3000);
DISPLAY 0.617021 (-1725 3000);
PAINT SKYBLUE (-1725 3000);
FORCEPROP 1 LAST LOCATION C1T10
J 0
(-1725 3050);
DISPLAY 0.617021 (-1725 3050);
PAINT AQUA (-1725 3050);
FORCEPROP 2 LAST CDS_LIB dev_discrete
J 0
(-1775 2950);
PAINT ORANGE (-1775 2950);
DISPLAY INVISIBLE (-1775 2950);
FORCEPROP 2 LAST CDS_LOCATION C1T10
J 0
(-1725 3050);
DISPLAY 0.617021 (-1725 3050);
PAINT AQUA (-1725 3050);
DISPLAY INVISIBLE (-1725 3050);
FORCEPROP 1 LAST PATH I70
J 0
(-1725 3100);
DISPLAY 0.978723 (-1725 3100);
PAINT WHITE (-1725 3100);
DISPLAY INVISIBLE (-1725 3100);
FORCEPROP 2 LAST BOM_COST DEBUG
J 0
(-1725 3150);
DISPLAY 1.021277 (-1725 3150);
PAINT ORANGE (-1725 3150);
DISPLAY INVISIBLE (-1725 3150);
FORCEPROP 2 LAST CDS_SEC 1
J 0
(-1725 3100);
PAINT ORANGE (-1725 3100);
DISPLAY INVISIBLE (-1725 3100);
FORCEPROP 2 LAST SEC_TYPE 0402V
J 0
(-1725 3150);
DISPLAY 1.021277 (-1725 3150);
PAINT ORANGE (-1725 3150);
DISPLAY INVISIBLE (-1725 3150);
FORCEPROP 2 LAST SEC 1
J 0
(-1725 3150);
DISPLAY 0.680851 (-1725 3150);
PAINT MONO (-1725 3150);
DISPLAY INVISIBLE (-1725 3150);
FORCEPROP 2 LAST ROOM UART_MUX
J 0
(-1725 3100);
DISPLAY 1.021277 (-1725 3100);
PAINT ORANGE (-1725 3100);
DISPLAY INVISIBLE (-1725 3100);
FORCEADD GND..1
(-1775 2725);
FORCEPROP 3 LASTPIN (-1775 2775) SIG_NAME GND\g
J 0
(-1765 2785);
DISPLAY 0.659574 (-1765 2785);
PAINT MONO (-1765 2785);
DISPLAY INVISIBLE (-1765 2785);
FORCEPROP 1 LAST BODY_TYPE PLUMBING
J 0
(-1820 2682);
DISPLAY 0.340426 (-1820 2682);
PAINT GREEN (-1820 2682);
DISPLAY INVISIBLE (-1820 2682);
FORCEPROP 1 LAST VOLTAGE 0.0V
J 0
(-1820 2682);
DISPLAY 0.340426 (-1820 2682);
PAINT SKYBLUE (-1820 2682);
DISPLAY INVISIBLE (-1820 2682);
FORCEPROP 1 LAST PATH I72
J 0
(-1700 2725);
DISPLAY 0.872340 (-1700 2725);
PAINT AQUA (-1700 2725);
DISPLAY INVISIBLE (-1700 2725);
FORCEPROP 1 LAST SIZE 1B
J 0
(-1700 2675);
DISPLAY 0.872340 (-1700 2675);
PAINT AQUA (-1700 2675);
DISPLAY INVISIBLE (-1700 2675);
FORCEPROP 2 LAST CDS_LIB mstr_symbols
J 0
(-1775 2725);
PAINT ORANGE (-1775 2725);
DISPLAY INVISIBLE (-1775 2725);
FORCEPROP 1 LAST HDL_POWER GND
J 0
(-1775 2875);
DISPLAY 0.872340 (-1775 2875);
PAINT GREEN (-1775 2875);
DISPLAY INVISIBLE (-1775 2875);
FORCEADD FSA3357..1
R 2
(-2275 2575);
FORCEPROP 2 LASTPIN (-2525 2675) $PN 3
J 2
(-2535 2685);
DISPLAY 0.617021 (-2535 2685);
PAINT ORANGE (-2535 2685);
FORCEPROP 2 LASTPIN (-2525 2575) $PN 1
J 2
(-2535 2585);
DISPLAY 0.617021 (-2535 2585);
PAINT ORANGE (-2535 2585);
FORCEPROP 1 LAST MATERIAL IC
J 2
(-2075 2925);
DISPLAY 0.617021 (-2075 2925);
PAINT SKYBLUE (-2075 2925);
FORCEPROP 2 LASTPIN (-2025 2475) $PN 6
J 0
(-2015 2485);
DISPLAY 0.617021 (-2015 2485);
PAINT ORANGE (-2015 2485);
FORCEPROP 2 LASTPIN (-2025 2525) $PN 5
J 0
(-2015 2535);
DISPLAY 0.617021 (-2015 2535);
PAINT ORANGE (-2015 2535);
FORCEPROP 2 LASTPIN (-2525 2625) $PN 2
J 2
(-2535 2635);
DISPLAY 0.617021 (-2535 2635);
PAINT ORANGE (-2535 2635);
FORCEPROP 2 LASTPIN (-2025 2625) $PN 7
J 0
(-2015 2635);
DISPLAY 0.617021 (-2015 2635);
PAINT ORANGE (-2015 2635);
FORCEPROP 2 LASTPIN (-2025 2725) $PN 8
J 0
(-2015 2735);
DISPLAY 0.617021 (-2015 2735);
PAINT ORANGE (-2015 2735);
FORCEPROP 2 LASTPIN (-2525 2325) $PN 4
J 2
(-2535 2335);
DISPLAY 0.617021 (-2535 2335);
PAINT ORANGE (-2535 2335);
FORCEPROP 1 LAST LOCATION U9F2
J 2
(-2075 2975);
DISPLAY 0.617021 (-2075 2975);
PAINT AQUA (-2075 2975);
FORCEPROP 1 LAST PART_NUMBER C63273-001
J 2
(-2075 2225);
DISPLAY 0.617021 (-2075 2225);
PAINT BLUE (-2075 2225);
FORCEPROP 2 LAST CDS_LIB mstr_analog
J 2
(-2275 2575);
PAINT MONO (-2275 2575);
DISPLAY INVISIBLE (-2275 2575);
FORCEPROP 2 LAST SEC_TYPE SM
J 0
(-2075 3025);
DISPLAY 1.021277 (-2075 3025);
PAINT ORANGE (-2075 3025);
DISPLAY INVISIBLE (-2075 3025);
FORCEPROP 2 LAST SEC 1
J 0
(-2075 3025);
DISPLAY 0.680851 (-2075 3025);
PAINT MONO (-2075 3025);
DISPLAY INVISIBLE (-2075 3025);
FORCEPROP 2 LAST CDS_LOCATION U9F2
J 2
(-2075 2975);
DISPLAY 0.617021 (-2075 2975);
PAINT AQUA (-2075 2975);
DISPLAY INVISIBLE (-2075 2975);
FORCEPROP 1 LAST PATH I74
J 2
(-2275 2925);
PAINT GREEN (-2275 2925);
DISPLAY INVISIBLE (-2275 2925);
FORCEPROP 2 LAST ROOM UART_MUX
J 0
(-2075 3025);
DISPLAY 1.021277 (-2075 3025);
PAINT ORANGE (-2075 3025);
DISPLAY INVISIBLE (-2075 3025);
FORCEPROP 1 LAST PACK_TYPE SM
J 2
(-2075 3025);
PAINT SKYBLUE (-2075 3025);
DISPLAY INVISIBLE (-2075 3025);
FORCEPROP 2 LAST BOM_COST DEBUG
J 0
(-2075 3075);
DISPLAY 1.021277 (-2075 3075);
PAINT ORANGE (-2075 3075);
DISPLAY INVISIBLE (-2075 3075);
FORCEADD FSA3357..1
(-2650 850);
FORCEPROP 2 LASTPIN (-2400 850) $PN 1
J 0
(-2390 860);
DISPLAY 0.617021 (-2390 860);
PAINT ORANGE (-2390 860);
FORCEPROP 2 LASTPIN (-2900 800) $PN 5
J 2
(-2910 810);
DISPLAY 0.617021 (-2910 810);
PAINT ORANGE (-2910 810);
FORCEPROP 1 LAST PART_NUMBER C63273-001
J 0
(-2850 500);
DISPLAY 0.617021 (-2850 500);
PAINT BLUE (-2850 500);
FORCEPROP 1 LAST LOCATION U9F1
J 0
(-2850 1250);
DISPLAY 0.617021 (-2850 1250);
PAINT AQUA (-2850 1250);
FORCEPROP 1 LAST MATERIAL IC
J 0
(-2850 1200);
DISPLAY 0.617021 (-2850 1200);
PAINT SKYBLUE (-2850 1200);
FORCEPROP 2 LASTPIN (-2900 900) $PN 7
J 2
(-2910 910);
DISPLAY 0.617021 (-2910 910);
PAINT ORANGE (-2910 910);
FORCEPROP 2 LASTPIN (-2900 750) $PN 6
J 2
(-2910 760);
DISPLAY 0.617021 (-2910 760);
PAINT ORANGE (-2910 760);
FORCEPROP 2 LASTPIN (-2400 600) $PN 4
J 0
(-2390 610);
DISPLAY 0.617021 (-2390 610);
PAINT ORANGE (-2390 610);
FORCEPROP 2 LASTPIN (-2400 900) $PN 2
J 0
(-2390 910);
DISPLAY 0.617021 (-2390 910);
PAINT ORANGE (-2390 910);
FORCEPROP 2 LASTPIN (-2400 950) $PN 3
J 0
(-2390 960);
DISPLAY 0.617021 (-2390 960);
PAINT ORANGE (-2390 960);
FORCEPROP 2 LASTPIN (-2900 1000) $PN 8
J 2
(-2910 1010);
DISPLAY 0.617021 (-2910 1010);
PAINT ORANGE (-2910 1010);
FORCEPROP 2 LAST CDS_LIB mstr_analog
J 0
(-2650 850);
PAINT MONO (-2650 850);
DISPLAY INVISIBLE (-2650 850);
FORCEPROP 2 LAST SEC_TYPE SM
J 0
(-2850 1300);
DISPLAY 1.021277 (-2850 1300);
PAINT ORANGE (-2850 1300);
DISPLAY INVISIBLE (-2850 1300);
FORCEPROP 2 LAST SEC 1
J 0
(-2850 1300);
DISPLAY 0.680851 (-2850 1300);
PAINT MONO (-2850 1300);
DISPLAY INVISIBLE (-2850 1300);
FORCEPROP 2 LAST CDS_LOCATION U9F1
J 0
(-2850 1250);
DISPLAY 0.617021 (-2850 1250);
PAINT AQUA (-2850 1250);
DISPLAY INVISIBLE (-2850 1250);
FORCEPROP 2 LAST BOM_COST DEBUG
J 0
(-2850 1350);
DISPLAY 1.021277 (-2850 1350);
PAINT ORANGE (-2850 1350);
DISPLAY INVISIBLE (-2850 1350);
FORCEPROP 2 LAST ROOM UART_MUX
J 0
(-2850 1300);
DISPLAY 1.021277 (-2850 1300);
PAINT ORANGE (-2850 1300);
DISPLAY INVISIBLE (-2850 1300);
FORCEPROP 1 LAST PACK_TYPE SM
J 0
(-2850 1300);
PAINT SKYBLUE (-2850 1300);
DISPLAY INVISIBLE (-2850 1300);
FORCEPROP 1 LAST PATH I75
J 0
(-2650 1200);
PAINT GREEN (-2650 1200);
DISPLAY INVISIBLE (-2650 1200);
FORCEADD GND..1
(-2625 2125);
FORCEPROP 3 LASTPIN (-2625 2175) SIG_NAME GND\g
J 0
(-2615 2185);
DISPLAY 0.659574 (-2615 2185);
PAINT MONO (-2615 2185);
DISPLAY INVISIBLE (-2615 2185);
FORCEPROP 2 LAST CDS_LIB mstr_symbols
J 0
(-2625 2125);
PAINT MONO (-2625 2125);
DISPLAY INVISIBLE (-2625 2125);
FORCEPROP 1 LAST BODY_TYPE PLUMBING
J 0
(-2670 2082);
DISPLAY 0.340426 (-2670 2082);
PAINT GREEN (-2670 2082);
DISPLAY INVISIBLE (-2670 2082);
FORCEPROP 1 LAST HDL_POWER GND
J 0
(-2625 2275);
DISPLAY 0.872340 (-2625 2275);
PAINT GREEN (-2625 2275);
DISPLAY INVISIBLE (-2625 2275);
FORCEPROP 1 LAST VOLTAGE 0.0V
J 0
(-2670 2082);
DISPLAY 0.340426 (-2670 2082);
PAINT SKYBLUE (-2670 2082);
DISPLAY INVISIBLE (-2670 2082);
FORCEPROP 1 LAST SIZE 1B
J 0
(-2550 2075);
DISPLAY 0.872340 (-2550 2075);
PAINT AQUA (-2550 2075);
DISPLAY INVISIBLE (-2550 2075);
FORCEPROP 1 LAST PATH I76
J 0
(-2550 2125);
DISPLAY 0.872340 (-2550 2125);
PAINT AQUA (-2550 2125);
DISPLAY INVISIBLE (-2550 2125);
FORCEADD GND..1
(-2325 425);
FORCEPROP 3 LASTPIN (-2325 475) SIG_NAME GND\g
J 0
(-2315 485);
DISPLAY 0.659574 (-2315 485);
PAINT MONO (-2315 485);
DISPLAY INVISIBLE (-2315 485);
FORCEPROP 2 LAST CDS_LIB mstr_symbols
J 0
(-2325 425);
PAINT MONO (-2325 425);
DISPLAY INVISIBLE (-2325 425);
FORCEPROP 1 LAST SIZE 1B
J 0
(-2250 375);
DISPLAY 0.872340 (-2250 375);
PAINT AQUA (-2250 375);
DISPLAY INVISIBLE (-2250 375);
FORCEPROP 1 LAST BODY_TYPE PLUMBING
J 0
(-2370 382);
DISPLAY 0.340426 (-2370 382);
PAINT GREEN (-2370 382);
DISPLAY INVISIBLE (-2370 382);
FORCEPROP 1 LAST PATH I77
J 0
(-2250 425);
DISPLAY 0.872340 (-2250 425);
PAINT AQUA (-2250 425);
DISPLAY INVISIBLE (-2250 425);
FORCEPROP 1 LAST VOLTAGE 0.0V
J 0
(-2370 382);
DISPLAY 0.340426 (-2370 382);
PAINT SKYBLUE (-2370 382);
DISPLAY INVISIBLE (-2370 382);
FORCEPROP 1 LAST HDL_POWER GND
J 0
(-2325 575);
DISPLAY 0.872340 (-2325 575);
PAINT GREEN (-2325 575);
DISPLAY INVISIBLE (-2325 575);
FORCEADD P3V3_STBY..1
(-1950 3150);
FORCEPROP 3 LASTPIN (-1950 3100) SIG_NAME P3V3_STBY\g
J 0
(-1940 3110);
DISPLAY 0.659574 (-1940 3110);
PAINT MONO (-1940 3110);
DISPLAY INVISIBLE (-1940 3110);
FORCEPROP 1 LAST HDL_POWER P3V3_STBY
J 0
(-2250 3025);
DISPLAY 0.872340 (-2250 3025);
PAINT ORANGE (-2250 3025);
DISPLAY INVISIBLE (-2250 3025);
FORCEPROP 1 LAST VOLTAGE 3.3V
J 0
(-1995 3107);
DISPLAY 0.340426 (-1995 3107);
PAINT SKYBLUE (-1995 3107);
DISPLAY INVISIBLE (-1995 3107);
FORCEPROP 1 LAST BODY_TYPE PLUMBING
J 0
(-1995 3107);
DISPLAY 0.340426 (-1995 3107);
PAINT GREEN (-1995 3107);
DISPLAY INVISIBLE (-1995 3107);
FORCEPROP 2 LAST CDS_LIB mstr_symbols
J 0
(-1950 3150);
PAINT MONO (-1950 3150);
DISPLAY INVISIBLE (-1950 3150);
FORCEPROP 1 LAST PATH I78
J 0
(-1905 3152);
DISPLAY 0.340426 (-1905 3152);
PAINT GREEN (-1905 3152);
DISPLAY INVISIBLE (-1905 3152);
FORCEPROP 1 LAST SIZE 1B
J 0
(-1905 3172);
DISPLAY 0.340426 (-1905 3172);
PAINT GREEN (-1905 3172);
DISPLAY INVISIBLE (-1905 3172);
FORCEADD P3V3_STBY..1
(-3100 1425);
FORCEPROP 3 LASTPIN (-3100 1375) SIG_NAME P3V3_STBY\g
J 0
(-3090 1385);
DISPLAY 0.659574 (-3090 1385);
PAINT MONO (-3090 1385);
DISPLAY INVISIBLE (-3090 1385);
FORCEPROP 1 LAST HDL_POWER P3V3_STBY
J 0
(-3400 1300);
DISPLAY 0.872340 (-3400 1300);
PAINT ORANGE (-3400 1300);
DISPLAY INVISIBLE (-3400 1300);
FORCEPROP 1 LAST VOLTAGE 3.3V
J 0
(-3145 1382);
DISPLAY 0.340426 (-3145 1382);
PAINT SKYBLUE (-3145 1382);
DISPLAY INVISIBLE (-3145 1382);
FORCEPROP 1 LAST BODY_TYPE PLUMBING
J 0
(-3145 1382);
DISPLAY 0.340426 (-3145 1382);
PAINT GREEN (-3145 1382);
DISPLAY INVISIBLE (-3145 1382);
FORCEPROP 2 LAST CDS_LIB mstr_symbols
J 0
(-3100 1425);
PAINT MONO (-3100 1425);
DISPLAY INVISIBLE (-3100 1425);
FORCEPROP 1 LAST SIZE 1B
J 0
(-3055 1447);
DISPLAY 0.340426 (-3055 1447);
PAINT GREEN (-3055 1447);
DISPLAY INVISIBLE (-3055 1447);
FORCEPROP 1 LAST PATH I79
J 0
(-3055 1427);
DISPLAY 0.340426 (-3055 1427);
PAINT GREEN (-3055 1427);
DISPLAY INVISIBLE (-3055 1427);
FORCEADD OFFPAGE..2
(-600 2625);
FORCEPROP 2 LAST $XR2 181 
J 0
(-291 2625);
DISPLAY 0.638298 (-291 2625);
PAINT MONO (-291 2625);
FORCEPROP 2 LAST $XR1 155 
J 0
(-291 2625);
DISPLAY 0.638298 (-291 2625);
PAINT MONO (-291 2625);
FORCEPROP 2 LAST $XR0 176 
J 0
(-411 2625);
DISPLAY 0.638298 (-411 2625);
PAINT MONO (-411 2625);
FORCEPROP 1 LAST COMMENT_BODY TRUE
J 0
(-645 2530);
DISPLAY 0.872340 (-645 2530);
PAINT GREEN (-645 2530);
DISPLAY INVISIBLE (-645 2530);
FORCEPROP 2 LAST PATH I85
J 0
(-550 2700);
DISPLAY 1.021277 (-550 2700);
PAINT ORANGE (-550 2700);
DISPLAY INVISIBLE (-550 2700);
FORCEPROP 2 LAST CDS_LIB mstr_standard
J 0
(-600 2625);
PAINT MONO (-600 2625);
DISPLAY INVISIBLE (-600 2625);
FORCEPROP 1 LAST OFFPAGE TRUE
J 0
(-275 2500);
DISPLAY 0.872340 (-275 2500);
PAINT GREEN (-275 2500);
DISPLAY INVISIBLE (-275 2500);
FORCEADD RES..1
(-3625 900);
FORCEPROP 1 LAST PACK_TYPE 0402
J 0
(-3150 850);
DISPLAY 0.617021 (-3150 850);
PAINT SKYBLUE (-3150 850);
FORCEPROP 1 LAST VALUE 100.0
J 2
(-3750 850);
DISPLAY 0.617021 (-3750 850);
PAINT SKYBLUE (-3750 850);
FORCEPROP 1 LASTPIN (-3725 900) $PN 1
J 0
(-3713 912);
DISPLAY 0.617021 (-3713 912);
PAINT ORANGE (-3713 912);
FORCEPROP 1 LAST LOCATION R9F25
J 0
(-3675 950);
DISPLAY 0.617021 (-3675 950);
PAINT AQUA (-3675 950);
FORCEPROP 1 LASTPIN (-3525 900) $PN 2
J 0
(-3563 912);
DISPLAY 0.617021 (-3563 912);
PAINT ORANGE (-3563 912);
FORCEPROP 1 LAST TOLERANCE 1%
J 0
(-3475 850);
DISPLAY 0.617021 (-3475 850);
PAINT SKYBLUE (-3475 850);
FORCEPROP 1 LAST PART_NUMBER G21796-017
J 0
(-3400 850);
DISPLAY 0.617021 (-3400 850);
PAINT BLUE (-3400 850);
FORCEPROP 1 LAST MATERIAL CHIP
J 0
(-3675 850);
DISPLAY 0.617021 (-3675 850);
PAINT SKYBLUE (-3675 850);
FORCEPROP 1 LAST WATTAGE 1/16W
J 2
(-3900 850);
DISPLAY 0.617021 (-3900 850);
PAINT SKYBLUE (-3900 850);
FORCEPROP 2 LAST CDS_LOCATION R9F25
J 0
(-3675 950);
DISPLAY 0.617021 (-3675 950);
PAINT AQUA (-3675 950);
DISPLAY INVISIBLE (-3675 950);
FORCEPROP 2 LAST CDS_LIB mstr_discrete
J 0
(-3625 900);
PAINT ORANGE (-3625 900);
DISPLAY INVISIBLE (-3625 900);
FORCEPROP 2 LAST ROOM UART_MUX
J 0
(-3625 1000);
DISPLAY 1.021277 (-3625 1000);
PAINT ORANGE (-3625 1000);
DISPLAY INVISIBLE (-3625 1000);
FORCEPROP 2 LAST SEC_TYPE 0402
J 0
(-3675 1100);
DISPLAY 1.021277 (-3675 1100);
PAINT ORANGE (-3675 1100);
DISPLAY INVISIBLE (-3675 1100);
FORCEPROP 2 LAST SEC 1
J 0
(-3675 1100);
DISPLAY 0.680851 (-3675 1100);
PAINT MONO (-3675 1100);
DISPLAY INVISIBLE (-3675 1100);
FORCEPROP 1 LAST PATH I86
J 0
(-3675 1050);
DISPLAY 0.978723 (-3675 1050);
PAINT WHITE (-3675 1050);
DISPLAY INVISIBLE (-3675 1050);
FORCEPROP 2 LAST BOM_COST DEBUG
J 0
(-3625 1050);
DISPLAY 1.021277 (-3625 1050);
PAINT ORANGE (-3625 1050);
DISPLAY INVISIBLE (-3625 1050);
FORCEADD OFFPAGE..1
(-4725 900);
FORCEPROP 2 LAST $XR1 181 
J 0
(-5097 900);
DISPLAY 0.638298 (-5097 900);
PAINT MONO (-5097 900);
FORCEPROP 2 LAST $XR0 176 
J 0
(-4977 900);
DISPLAY 0.638298 (-4977 900);
PAINT MONO (-4977 900);
FORCEPROP 2 LAST PATH I87
J 0
(-4675 975);
DISPLAY 1.021277 (-4675 975);
PAINT ORANGE (-4675 975);
DISPLAY INVISIBLE (-4675 975);
FORCEPROP 2 LAST CDS_LIB mstr_standard
J 0
(-4725 900);
PAINT MONO (-4725 900);
DISPLAY INVISIBLE (-4725 900);
FORCEPROP 1 LAST OFFPAGE TRUE
J 0
(-4400 775);
DISPLAY 0.872340 (-4400 775);
PAINT GREEN (-4400 775);
DISPLAY INVISIBLE (-4400 775);
FORCEPROP 1 LAST COMMENT_BODY TRUE
J 0
(-4600 800);
DISPLAY 0.872340 (-4600 800);
PAINT GREEN (-4600 800);
DISPLAY INVISIBLE (-4600 800);
FORCEADD RES..1
(-1325 2625);
FORCEPROP 1 LAST MATERIAL CHIP
J 0
(-1175 2575);
DISPLAY 0.617021 (-1175 2575);
PAINT SKYBLUE (-1175 2575);
FORCEPROP 1 LAST WATTAGE 1/16W
J 2
(-1425 2575);
DISPLAY 0.617021 (-1425 2575);
PAINT SKYBLUE (-1425 2575);
FORCEPROP 1 LASTPIN (-1425 2625) $PN 1
J 0
(-1413 2637);
DISPLAY 0.617021 (-1413 2637);
PAINT ORANGE (-1413 2637);
FORCEPROP 1 LAST VALUE 0.0
J 2
(-1350 2575);
DISPLAY 0.617021 (-1350 2575);
PAINT SKYBLUE (-1350 2575);
FORCEPROP 1 LAST LOCATION R9F27
J 0
(-1375 2675);
DISPLAY 0.617021 (-1375 2675);
PAINT AQUA (-1375 2675);
FORCEPROP 1 LASTPIN (-1225 2625) $PN 2
J 0
(-1263 2637);
DISPLAY 0.617021 (-1263 2637);
PAINT ORANGE (-1263 2637);
FORCEPROP 1 LAST PACK_TYPE 0402
J 0
(-1075 2575);
DISPLAY 0.617021 (-1075 2575);
PAINT SKYBLUE (-1075 2575);
FORCEPROP 1 LAST TOLERANCE 5%
J 0
(-1250 2575);
DISPLAY 0.617021 (-1250 2575);
PAINT SKYBLUE (-1250 2575);
FORCEPROP 1 LAST PART_NUMBER G21497-005
J 0
(-1475 2500);
DISPLAY 0.617021 (-1475 2500);
PAINT BLUE (-1475 2500);
FORCEPROP 2 LAST ROOM UART_MUX
J 0
(-1325 2725);
DISPLAY 1.021277 (-1325 2725);
PAINT ORANGE (-1325 2725);
DISPLAY INVISIBLE (-1325 2725);
FORCEPROP 1 LAST PATH I91
J 0
(-1375 2775);
DISPLAY 0.978723 (-1375 2775);
PAINT WHITE (-1375 2775);
DISPLAY INVISIBLE (-1375 2775);
FORCEPROP 2 LAST CDS_LIB mstr_discrete
J 0
(-1325 2625);
PAINT MONO (-1325 2625);
DISPLAY INVISIBLE (-1325 2625);
FORCEPROP 2 LAST CDS_LOCATION R9F27
J 0
(-1375 2675);
DISPLAY 0.617021 (-1375 2675);
PAINT AQUA (-1375 2675);
DISPLAY INVISIBLE (-1375 2675);
FORCEPROP 2 LAST BOM_COST DEBUG
J 0
(-1325 2775);
DISPLAY 1.021277 (-1325 2775);
PAINT ORANGE (-1325 2775);
DISPLAY INVISIBLE (-1325 2775);
FORCEPROP 2 LAST SEC 1
J 0
(-1375 2825);
PAINT MONO (-1375 2825);
DISPLAY INVISIBLE (-1375 2825);
FORCEPROP 2 LAST SEC_TYPE 0402
J 0
(-1375 2825);
DISPLAY 1.021277 (-1375 2825);
PAINT ORANGE (-1375 2825);
DISPLAY INVISIBLE (-1375 2825);
FORCEADD OFFPAGE..1
(-4725 800);
FORCEPROP 2 LAST $XR3 158 
J 0
(-5337 800);
DISPLAY 0.638298 (-5337 800);
PAINT MONO (-5337 800);
FORCEPROP 2 LAST $XR2 120 
J 0
(-5217 800);
DISPLAY 0.638298 (-5217 800);
PAINT MONO (-5217 800);
FORCEPROP 2 LAST $XR1 190 
J 0
(-5097 800);
DISPLAY 0.638298 (-5097 800);
PAINT MONO (-5097 800);
FORCEPROP 2 LAST $XR0 147 
J 0
(-4977 800);
DISPLAY 0.638298 (-4977 800);
PAINT MONO (-4977 800);
FORCEPROP 2 LAST PATH I92
J 0
(-5000 850);
DISPLAY 1.021277 (-5000 850);
PAINT ORANGE (-5000 850);
DISPLAY INVISIBLE (-5000 850);
FORCEPROP 2 LAST CDS_LIB mstr_standard
J 0
(-4725 800);
PAINT ORANGE (-4725 800);
DISPLAY INVISIBLE (-4725 800);
FORCEPROP 1 LAST OFFPAGE TRUE
J 0
(-4400 675);
DISPLAY 0.872340 (-4400 675);
PAINT GREEN (-4400 675);
DISPLAY INVISIBLE (-4400 675);
FORCEPROP 1 LAST COMMENT_BODY TRUE
J 0
(-4600 700);
DISPLAY 0.872340 (-4600 700);
PAINT GREEN (-4600 700);
DISPLAY INVISIBLE (-4600 700);
FORCEADD OFFPAGE..1
(-4725 750);
FORCEPROP 2 LAST $XR2 120 
J 0
(-5217 750);
DISPLAY 0.638298 (-5217 750);
PAINT MONO (-5217 750);
FORCEPROP 2 LAST $XR1 190 
J 0
(-5097 750);
DISPLAY 0.638298 (-5097 750);
PAINT MONO (-5097 750);
FORCEPROP 2 LAST $XR3 158 
J 0
(-5337 750);
DISPLAY 0.638298 (-5337 750);
PAINT MONO (-5337 750);
FORCEPROP 2 LAST $XR0 147 
J 0
(-4977 750);
DISPLAY 0.638298 (-4977 750);
PAINT MONO (-4977 750);
FORCEPROP 2 LAST PATH I93
J 0
(-5000 800);
DISPLAY 1.021277 (-5000 800);
PAINT ORANGE (-5000 800);
DISPLAY INVISIBLE (-5000 800);
FORCEPROP 2 LAST CDS_LIB mstr_standard
J 0
(-4725 750);
PAINT ORANGE (-4725 750);
DISPLAY INVISIBLE (-4725 750);
FORCEPROP 1 LAST OFFPAGE TRUE
J 0
(-4400 625);
DISPLAY 0.872340 (-4400 625);
PAINT GREEN (-4400 625);
DISPLAY INVISIBLE (-4400 625);
FORCEPROP 1 LAST COMMENT_BODY TRUE
J 0
(-4600 650);
DISPLAY 0.872340 (-4600 650);
PAINT GREEN (-4600 650);
DISPLAY INVISIBLE (-4600 650);
FORCEADD OFFPAGE..1
(-3500 1975);
FORCEPROP 2 LAST $XR0 147 
J 0
(-3752 1975);
DISPLAY 0.638298 (-3752 1975);
PAINT MONO (-3752 1975);
FORCEPROP 2 LAST $XR1 190 
J 0
(-3872 1975);
DISPLAY 0.638298 (-3872 1975);
PAINT MONO (-3872 1975);
FORCEPROP 2 LAST $XR2 120 
J 0
(-3992 1975);
DISPLAY 0.638298 (-3992 1975);
PAINT MONO (-3992 1975);
FORCEPROP 2 LAST $XR3 158 
J 0
(-4112 1975);
DISPLAY 0.638298 (-4112 1975);
PAINT MONO (-4112 1975);
FORCEPROP 2 LAST CDS_LIB mstr_standard
J 0
(-3500 1975);
PAINT ORANGE (-3500 1975);
DISPLAY INVISIBLE (-3500 1975);
FORCEPROP 1 LAST COMMENT_BODY TRUE
J 0
(-3375 1875);
DISPLAY 0.872340 (-3375 1875);
PAINT GREEN (-3375 1875);
DISPLAY INVISIBLE (-3375 1875);
FORCEPROP 1 LAST OFFPAGE TRUE
J 0
(-3175 1850);
DISPLAY 0.872340 (-3175 1850);
PAINT GREEN (-3175 1850);
DISPLAY INVISIBLE (-3175 1850);
FORCEPROP 2 LAST PATH I94
J 0
(-3775 2025);
DISPLAY 1.021277 (-3775 2025);
PAINT ORANGE (-3775 2025);
DISPLAY INVISIBLE (-3775 2025);
FORCEADD OFFPAGE..1
(-3500 2025);
FORCEPROP 2 LAST $XR0 147 
J 0
(-3752 2025);
DISPLAY 0.638298 (-3752 2025);
PAINT MONO (-3752 2025);
FORCEPROP 2 LAST $XR1 190 
J 0
(-3872 2025);
DISPLAY 0.638298 (-3872 2025);
PAINT MONO (-3872 2025);
FORCEPROP 2 LAST $XR2 120 
J 0
(-3992 2025);
DISPLAY 0.638298 (-3992 2025);
PAINT MONO (-3992 2025);
FORCEPROP 2 LAST $XR3 158 
J 0
(-4112 2025);
DISPLAY 0.638298 (-4112 2025);
PAINT MONO (-4112 2025);
FORCEPROP 1 LAST COMMENT_BODY TRUE
J 0
(-3375 1925);
DISPLAY 0.872340 (-3375 1925);
PAINT GREEN (-3375 1925);
DISPLAY INVISIBLE (-3375 1925);
FORCEPROP 1 LAST OFFPAGE TRUE
J 0
(-3175 1900);
DISPLAY 0.872340 (-3175 1900);
PAINT GREEN (-3175 1900);
DISPLAY INVISIBLE (-3175 1900);
FORCEPROP 2 LAST CDS_LIB mstr_standard
J 0
(-3500 2025);
PAINT ORANGE (-3500 2025);
DISPLAY INVISIBLE (-3500 2025);
FORCEPROP 2 LAST PATH I95
J 0
(-3775 2075);
DISPLAY 1.021277 (-3775 2075);
PAINT ORANGE (-3775 2075);
DISPLAY INVISIBLE (-3775 2075);
FORCEADD CAP_A..1
(-3475 1200);
FORCEPROP 1 LAST PACK_TYPE 0402V
J 0
(-3425 1000);
DISPLAY 0.617021 (-3425 1000);
PAINT SKYBLUE (-3425 1000);
FORCEPROP 1 LASTPIN (-3475 1100) $PN 2
J 0
(-3465 1080);
DISPLAY 0.617021 (-3465 1080);
PAINT ORANGE (-3465 1080);
FORCEPROP 1 LAST VOLTAGE 16V
J 0
(-3425 1200);
DISPLAY 0.617021 (-3425 1200);
PAINT SKYBLUE (-3425 1200);
FORCEPROP 1 LAST MATERIAL X7R
J 0
(-3425 1100);
DISPLAY 0.617021 (-3425 1100);
PAINT SKYBLUE (-3425 1100);
FORCEPROP 1 LAST TOLERANCE 10%
J 0
(-3425 1150);
DISPLAY 0.617021 (-3425 1150);
PAINT SKYBLUE (-3425 1150);
FORCEPROP 1 LASTPIN (-3475 1300) $PN 1
J 0
(-3465 1280);
DISPLAY 0.617021 (-3465 1280);
PAINT ORANGE (-3465 1280);
FORCEPROP 1 LAST VALUE 0.1UF
J 0
(-3425 1250);
DISPLAY 0.617021 (-3425 1250);
PAINT SKYBLUE (-3425 1250);
FORCEPROP 1 LAST LOCATION C1T11
J 0
(-3425 1300);
DISPLAY 0.617021 (-3425 1300);
PAINT AQUA (-3425 1300);
FORCEPROP 1 LAST PART_NUMBER A36096-030
J 0
(-3425 1050);
DISPLAY 0.617021 (-3425 1050);
PAINT BLUE (-3425 1050);
FORCEPROP 2 LAST CDS_LIB dev_discrete
J 0
(-3475 1200);
PAINT ORANGE (-3475 1200);
DISPLAY INVISIBLE (-3475 1200);
FORCEPROP 2 LAST SEC_TYPE 0402V
J 0
(-3425 1400);
DISPLAY 1.021277 (-3425 1400);
PAINT ORANGE (-3425 1400);
DISPLAY INVISIBLE (-3425 1400);
FORCEPROP 2 LAST BOM_COST DEBUG
J 0
(-3425 1400);
DISPLAY 1.021277 (-3425 1400);
PAINT ORANGE (-3425 1400);
DISPLAY INVISIBLE (-3425 1400);
FORCEPROP 2 LAST CDS_SEC 1
J 0
(-3425 1350);
PAINT ORANGE (-3425 1350);
DISPLAY INVISIBLE (-3425 1350);
FORCEPROP 1 LAST PATH I97
J 0
(-3425 1350);
DISPLAY 0.978723 (-3425 1350);
PAINT WHITE (-3425 1350);
DISPLAY INVISIBLE (-3425 1350);
FORCEPROP 2 LAST CDS_LOCATION C1T11
J 0
(-3425 1300);
DISPLAY 0.617021 (-3425 1300);
PAINT AQUA (-3425 1300);
DISPLAY INVISIBLE (-3425 1300);
FORCEPROP 2 LAST SEC 1
J 0
(-3425 1400);
DISPLAY 0.680851 (-3425 1400);
PAINT MONO (-3425 1400);
DISPLAY INVISIBLE (-3425 1400);
FORCEPROP 2 LAST ROOM UART_MUX
J 0
(-3425 1350);
DISPLAY 1.021277 (-3425 1350);
PAINT ORANGE (-3425 1350);
DISPLAY INVISIBLE (-3425 1350);
FORCEADD GND..1
(-3475 1000);
FORCEPROP 3 LASTPIN (-3475 1050) SIG_NAME GND\g
J 0
(-3465 1060);
DISPLAY 0.659574 (-3465 1060);
PAINT MONO (-3465 1060);
DISPLAY INVISIBLE (-3465 1060);
FORCEPROP 1 LAST BODY_TYPE PLUMBING
J 0
(-3520 957);
DISPLAY 0.340426 (-3520 957);
PAINT GREEN (-3520 957);
DISPLAY INVISIBLE (-3520 957);
FORCEPROP 1 LAST SIZE 1B
J 0
(-3400 950);
DISPLAY 0.872340 (-3400 950);
PAINT AQUA (-3400 950);
DISPLAY INVISIBLE (-3400 950);
FORCEPROP 1 LAST VOLTAGE 0.0V
J 0
(-3520 957);
DISPLAY 0.340426 (-3520 957);
PAINT SKYBLUE (-3520 957);
DISPLAY INVISIBLE (-3520 957);
FORCEPROP 2 LAST CDS_LIB mstr_symbols
J 0
(-3475 1000);
PAINT ORANGE (-3475 1000);
DISPLAY INVISIBLE (-3475 1000);
FORCEPROP 1 LAST PATH I98
J 0
(-3400 1000);
DISPLAY 0.872340 (-3400 1000);
PAINT AQUA (-3400 1000);
DISPLAY INVISIBLE (-3400 1000);
FORCEPROP 1 LAST HDL_POWER GND
J 0
(-3475 1150);
DISPLAY 0.872340 (-3475 1150);
PAINT GREEN (-3475 1150);
DISPLAY INVISIBLE (-3475 1150);
FORCEADD RES..1
(-1900 3450);
FORCEPROP 1 LASTPIN (-1800 3450) $PN 2
J 0
(-1838 3462);
DISPLAY 0.617021 (-1838 3462);
PAINT ORANGE (-1838 3462);
FORCEPROP 1 LASTPIN (-2000 3450) $PN 1
J 0
(-1988 3462);
DISPLAY 0.617021 (-1988 3462);
PAINT ORANGE (-1988 3462);
FORCEPROP 1 LAST LOCATION R9F26
J 0
(-1950 3500);
DISPLAY 0.617021 (-1950 3500);
PAINT AQUA (-1950 3500);
FORCEPROP 1 LAST PACK_TYPE 0402
J 0
(-1650 3300);
DISPLAY 0.617021 (-1650 3300);
PAINT SKYBLUE (-1650 3300);
FORCEPROP 1 LAST MATERIAL EMPTY
J 0
(-1900 3300);
DISPLAY 0.617021 (-1900 3300);
PAINT RED (-1900 3300);
FORCEPROP 1 LAST TOLERANCE 5%
J 0
(-1900 3350);
DISPLAY 0.617021 (-1900 3350);
PAINT SKYBLUE (-1900 3350);
FORCEPROP 1 LAST VALUE 0.0
J 2
(-1925 3350);
DISPLAY 0.617021 (-1925 3350);
PAINT SKYBLUE (-1925 3350);
FORCEPROP 1 LAST PART_NUMBER G21497-005
J 0
(-2000 3250);
DISPLAY 0.617021 (-2000 3250);
PAINT BLUE (-2000 3250);
FORCEPROP 1 LAST WATTAGE 1/16W
J 2
(-1925 3300);
DISPLAY 0.617021 (-1925 3300);
PAINT SKYBLUE (-1925 3300);
FORCEPROP 2 LAST CDS_LIB mstr_discrete
J 0
(-1900 3450);
PAINT ORANGE (-1900 3450);
DISPLAY INVISIBLE (-1900 3450);
FORCEPROP 2 LAST CDS_LOCATION R9F26
J 0
(-1950 3500);
DISPLAY 0.617021 (-1950 3500);
PAINT AQUA (-1950 3500);
DISPLAY INVISIBLE (-1950 3500);
FORCEPROP 2 LAST SEC 1
J 0
(-1950 3650);
DISPLAY 0.680851 (-1950 3650);
PAINT MONO (-1950 3650);
DISPLAY INVISIBLE (-1950 3650);
FORCEPROP 2 LAST SEC_TYPE 0402
J 0
(-1950 3650);
DISPLAY 1.021277 (-1950 3650);
PAINT ORANGE (-1950 3650);
DISPLAY INVISIBLE (-1950 3650);
FORCEPROP 1 LAST PATH I99
J 0
(-1950 3600);
DISPLAY 0.978723 (-1950 3600);
PAINT WHITE (-1950 3600);
DISPLAY INVISIBLE (-1950 3600);
FORCEPROP 2 LAST BOM_COST DEBUG
J 0
(-1950 3600);
DISPLAY 1.021277 (-1950 3600);
PAINT ORANGE (-1950 3600);
DISPLAY INVISIBLE (-1950 3600);
FORCEPROP 2 LAST ROOM UART_MUX
J 0
(-1950 3550);
DISPLAY 1.021277 (-1950 3550);
PAINT ORANGE (-1950 3550);
DISPLAY INVISIBLE (-1950 3550);
FORCEADD DNS..2
(-1895 3445);
PAINT RED (-1895 3445);
FORCEPROP 2 LAST CDS_LIB mstr_misc
J 0
(-1895 3445);
PAINT MONO (-1895 3445);
DISPLAY INVISIBLE (-1895 3445);
FORCEPROP 1 LAST COMMENT_BODY TRUE
R 1
J 0
(-1820 3220);
DISPLAY 0.872340 (-1820 3220);
PAINT GREEN (-1820 3220);
DISPLAY INVISIBLE (-1820 3220);
FORCEADD DNS..2
(-3145 2595);
PAINT RED (-3145 2595);
FORCEPROP 1 LAST COMMENT_BODY TRUE
R 1
J 0
(-3070 2370);
DISPLAY 0.872340 (-3070 2370);
PAINT GREEN (-3070 2370);
DISPLAY INVISIBLE (-3070 2370);
FORCEPROP 2 LAST CDS_LIB mstr_misc
J 0
(-3145 2595);
PAINT ORANGE (-3145 2595);
DISPLAY INVISIBLE (-3145 2595);
FORCEADD CAD_NOTE..1
(-3725 4075);
FORCEPROP 0 LAST L1 USE SHARED PADS FOR RESISTORS
J 0
(-3875 3950);
DISPLAY 0.808511 (-3875 3950);
PAINT ORANGE (-3875 3950);
FORCEPROP 0 LAST L2 ON NET SP2_BMC_CM_UART_TX_R
J 0
(-3875 3875);
DISPLAY 0.808511 (-3875 3875);
PAINT ORANGE (-3875 3875);
FORCEPROP 2 LAST CDS_LIB mstr_symbols
J 0
(-3725 4075);
PAINT ORANGE (-3725 4075);
DISPLAY INVISIBLE (-3725 4075);
FORCEPROP 1 LAST COMMENT_BODY TRUE
J 0
(-3700 4175);
DISPLAY 0.978723 (-3700 4175);
PAINT ORANGE (-3700 4175);
DISPLAY INVISIBLE (-3700 4175);
FORCEADD DESIGN_NOTE..1
(-5675 4350);
FORCEPROP 0 LAST L1 LED VALUES THE OPPOSITE OF MUX SELECT BITS
J 0
(-5875 4225);
DISPLAY 0.808511 (-5875 4225);
PAINT ORANGE (-5875 4225);
FORCEPROP 0 LAST L2 TO MEET LEGACY REQUIREMENTS. THIS IS BECAUSE
J 0
(-5875 4175);
DISPLAY 0.808511 (-5875 4175);
PAINT ORANGE (-5875 4175);
FORCEPROP 0 LAST L3 00 DISCONNECTS THE OUTPUT FROM THE INPUTS ON THE
J 0
(-5875 4125);
DISPLAY 0.808511 (-5875 4125);
PAINT ORANGE (-5875 4125);
FORCEPROP 0 LAST L4 FSA3357, WHILE PAST MUXES DID THIS WHEN S1 AND S2
J 0
(-5875 4075);
DISPLAY 0.808511 (-5875 4075);
PAINT ORANGE (-5875 4075);
FORCEPROP 0 LAST L5 WERE 11
J 0
(-5875 4025);
DISPLAY 0.808511 (-5875 4025);
PAINT ORANGE (-5875 4025);
FORCEPROP 2 LAST CDS_LIB mstr_symbols
J 0
(-5675 4350);
PAINT ORANGE (-5675 4350);
DISPLAY INVISIBLE (-5675 4350);
FORCEPROP 1 LAST COMMENT_BODY TRUE
J 0
(-5650 4450);
DISPLAY 0.978723 (-5650 4450);
PAINT ORANGE (-5650 4450);
DISPLAY INVISIBLE (-5650 4450);
FORCEADD CAD_NOTE..1
(-1350 2200);
FORCEPROP 0 LAST L2 ON NET SP2_BMC_CM_UART_RX_R
J 0
(-1500 2000);
DISPLAY 0.808511 (-1500 2000);
PAINT ORANGE (-1500 2000);
FORCEPROP 0 LAST L1 USE SHARED PADS FOR RESISTORS
J 0
(-1500 2075);
DISPLAY 0.808511 (-1500 2075);
PAINT ORANGE (-1500 2075);
FORCEPROP 1 LAST COMMENT_BODY TRUE
J 0
(-1325 2300);
DISPLAY 0.978723 (-1325 2300);
PAINT ORANGE (-1325 2300);
DISPLAY INVISIBLE (-1325 2300);
FORCEPROP 2 LAST CDS_LIB mstr_symbols
J 0
(-1350 2200);
PAINT ORANGE (-1350 2200);
DISPLAY INVISIBLE (-1350 2200);
FORCEADD DNS..2
(-1395 845);
PAINT RED (-1395 845);
FORCEPROP 2 LAST CDS_LIB mstr_misc
J 0
(-1395 845);
PAINT ORANGE (-1395 845);
DISPLAY INVISIBLE (-1395 845);
FORCEPROP 1 LAST COMMENT_BODY TRUE
R 1
J 0
(-1320 620);
DISPLAY 0.872340 (-1320 620);
PAINT GREEN (-1320 620);
DISPLAY INVISIBLE (-1320 620);
FORCEADD DNS..2
(-2645 1520);
PAINT RED (-2645 1520);
FORCEPROP 1 LAST COMMENT_BODY TRUE
R 1
J 0
(-2570 1295);
DISPLAY 0.872340 (-2570 1295);
PAINT GREEN (-2570 1295);
DISPLAY INVISIBLE (-2570 1295);
FORCEPROP 2 LAST CDS_LIB mstr_misc
J 0
(-2645 1520);
PAINT ORANGE (-2645 1520);
DISPLAY INVISIBLE (-2645 1520);
FORCEADD CAD_NOTE..1
(-7725 4800);
FORCEPROP 0 LAST L4 THE LEFT OF THE LSB LED
J 0
(-7875 4475);
DISPLAY 1.021277 (-7875 4475);
PAINT ORANGE (-7875 4475);
FORCEPROP 0 LAST L2 HEADER. WHEN LOOKING FROM BOARD EDGE, PLACE BOTH LEDS TO THE
J 0
(-7875 4625);
DISPLAY 1.021277 (-7875 4625);
PAINT ORANGE (-7875 4625);
FORCEPROP 0 LAST L1 PLACE LEDS NEAR BOARD EDGE NEXT TO BMC DEBUG
J 0
(-7875 4700);
DISPLAY 1.021277 (-7875 4700);
PAINT ORANGE (-7875 4700);
FORCEPROP 0 LAST L3 LEFT OF THE BMC DEBUG CONNECTOR. PLACE MSB LED ON
J 0
(-7875 4550);
DISPLAY 1.021277 (-7875 4550);
PAINT ORANGE (-7875 4550);
FORCEPROP 2 LAST CDS_LIB mstr_symbols
J 0
(-7725 4800);
PAINT MONO (-7725 4800);
DISPLAY INVISIBLE (-7725 4800);
FORCEPROP 1 LAST COMMENT_BODY TRUE
J 0
(-7700 4900);
DISPLAY 0.978723 (-7700 4900);
PAINT ORANGE (-7700 4900);
DISPLAY INVISIBLE (-7700 4900);
FORCEADD INTEL_CORP_BPAGE..1
(0 0);
FORCEPROP 1 LAST CDS_CON_LAST_MODIFIED Tue Dec 01 11:52:09 2015
J 0
(-1425 325);
DISPLAY 1.361702 (-1425 325);
PAINT GREEN (-1425 325);
DISPLAY INVISIBLE (-1425 325);
FORCEPROP 1 LAST CUSTOM_TXT_CDS <CURRENT_DESIGN_SHEET> OF <TOTAL_DESIGN_SHEETS>
J 0
(-500 25);
PAINT GREEN (-500 25);
FORCEPROP 1 LAST CUSTOM_TXT_CDS <CON_LAST_MODIFIED>
J 0
(-1925 350);
PAINT GREEN (-1925 350);
FORCEPROP 2 LAST CUSTOM_TXT_CDS <XR_PAGE_TITLE>
J 0
(-7890 5250);
DISPLAY 0.638298 (-7890 5250);
PAINT PINK (-7890 5250);
DISPLAY INVISIBLE (-7890 5250);
FORCEPROP 1 LAST SCH_NUMBER H4694802
J 0
(-1300 150);
DISPLAY 1.212766 (-1300 150);
PAINT YELLOW (-1300 150);
FORCEPROP 1 LAST SCH_DEPT BESD
J 1
(-4450 100);
DISPLAY 1.212766 (-4450 100);
PAINT YELLOW (-4450 100);
FORCEPROP 1 LAST SCH_TITLE UART MUX
J 0
(-7950 50);
DISPLAY 1.212766 (-7950 50);
PAINT ORANGE (-7950 50);
FORCEPROP 1 LAST SCH_REV 2.420
J 0
(-250 150);
DISPLAY 0.978723 (-250 150);
PAINT YELLOW (-250 150);
FORCEPROP 1 LAST SCH_ADDRESS2 P.O. BOX 58119
J 0
(-3975 75);
DISPLAY 0.617021 (-3975 75);
PAINT GREEN (-3975 75);
FORCEPROP 1 LAST SCH_ADDRESS3 Santa Clara, CA 95052-8119
J 0
(-3975 25);
DISPLAY 0.617021 (-3975 25);
PAINT GREEN (-3975 25);
FORCEPROP 1 LAST SCH_ADDRESS1 2200 Mission College Blvd.
J 0
(-3975 125);
DISPLAY 0.617021 (-3975 125);
PAINT GREEN (-3975 125);
FORCEPROP 2 LAST PAGE_BORDER TRUE
J 0
(-7890 5250);
DISPLAY 0.851064 (-7890 5250);
PAINT PINK (-7890 5250);
DISPLAY INVISIBLE (-7890 5250);
FORCEPROP 2 LAST CDS_LIB mstr_symbols
J 0
(0 0);
DISPLAY 1.361702 (0 0);
PAINT ORANGE (0 0);
DISPLAY INVISIBLE (0 0);
FORCEPROP 1 LAST COMMENT_BODY TRUE
J 0
(12 12);
DISPLAY 0.617021 (12 12);
PAINT GREEN (12 12);
DISPLAY INVISIBLE (12 12);
FORCEPROP 2 LAST CDS_XR_PAGE_TITLE CR-158 : @BASEBOARD_FAB2_LIB.BASEBOARD_FAB2(SCH_1):PAGE158
J 0
(-7890 5250);
DISPLAY 0.638298 (-7890 5250);
PAINT PINK (-7890 5250);
DISPLAY INVISIBLE (-7890 5250);
WIRE 16 -1 (-4400 3200)(-4400 3600);
WIRE 16 -1 (-4400 3200)(-4775 3200);
WIRE 16 -1 (-4400 3800)(-4400 3600);
WIRE 16 -1 (-4400 3600)(-4775 3600);
WIRE 16 -1 (-1775 2850)(-1775 2775);
WIRE 16 -1 (-2625 2325)(-2525 2325);
WIRE 16 -1 (-2625 2175)(-2625 2325);
WIRE 16 -1 (-2325 600)(-2400 600);
WIRE 16 -1 (-2325 475)(-2325 600);
WIRE 16 -1 (-1775 3050)(-1775 3075);
WIRE 16 -1 (-1775 3075)(-1950 3075);
WIRE 16 -1 (-1950 3075)(-1950 2725);
WIRE 16 -1 (-1950 3100)(-1950 3075);
WIRE 16 -1 (-1950 2725)(-2025 2725);
WIRE 16 -1 (-3100 1000)(-2900 1000);
WIRE 16 -1 (-3100 1350)(-3100 1000);
WIRE 16 -1 (-3475 1350)(-3100 1350);
WIRE 16 -1 (-3100 1375)(-3100 1350);
WIRE 16 -1 (-3475 1300)(-3475 1350);
WIRE 16 -1 (-3475 1100)(-3475 1050);
WIRE 16 -1 (-50 4675)(-50 4875);
WIRE 16 -1 (-50 4675)(-50 4350);
WIRE 16 -1 (-50 4675)(-4525 4675);
WIRE 16 -1 (-50 4875)(-1925 4875);
WIRE 16 -1 (-1925 4875)(-1925 4350);
WIRE 16 -1 (-2625 4875)(-1925 4875);
WIRE 16 -1 (-4525 4775)(-4525 4675);
WIRE 16 -1 (-4525 4350)(-4525 4675);
WIRE 16 -1 (-1925 4350)(-50 4350);
WIRE 16 -1 (-1925 4350)(-2625 4350);
WIRE 16 -1 (-4525 4350)(-3850 4350);
WIRE 16 -1 (-4525 4775)(-3850 4775);
WIRE 16 -1 (-4525 4875)(-4525 4775);
WIRE 16 -1 (-2625 4350)(-2625 4875);
WIRE 16 -1 (-3225 4875)(-2625 4875);
WIRE 16 -1 (-4525 4875)(-3225 4875);
WIRE 16 -1 (-3225 4875)(-3225 4775);
WIRE 16 -1 (-2625 4350)(-3225 4350);
WIRE 16 -1 (-3850 4775)(-3850 4350);
WIRE 16 -1 (-3850 4775)(-3225 4775);
WIRE 16 -1 (-3850 4350)(-3225 4350);
WIRE 16 -1 (-3225 4775)(-3225 4350);
WIRE 16 -1 (-7050 3600)(-5825 3600);
FORCEPROP 2 LAST SIG_NAME FM_UARTSW_MSB_N
J 0
(-7010 3610);
DISPLAY 0.617021 (-7010 3610);
PAINT ORANGE (-7010 3610);
WIRE 3 2175 (-1750 475)(-125 475);
WIRE 3 2175 (-1750 1925)(-1750 475);
WIRE 3 2175 (-125 1925)(-125 475);
WIRE 3 2175 (-1750 1925)(-125 1925);
WIRE 2 273 (-2750 2175)(-2750 4150);
WIRE 2 273 (-4325 2175)(-2750 2175);
WIRE 2 273 (-2750 4150)(-4325 4150);
WIRE 2 273 (-4325 4150)(-4325 2175);
WIRE 16 -1 (-3275 3450)(-2000 3450);
WIRE 16 -1 (-3275 3450)(-3275 2575);
WIRE 16 -1 (-3250 2575)(-3275 2575);
WIRE 16 -1 (-3275 2575)(-3900 2575);
FORCEPROP 2 LAST SIG_NAME SP2_BMC_CM_UART_TX
J 0
(-3810 2585);
DISPLAY 0.617021 (-3810 2585);
PAINT ORANGE (-3810 2585);
WIRE 16 -1 (-4975 3600)(-5625 3600);
FORCEPROP 2 LAST SIG_NAME FM_UARTSW_MSB_R_N
J 0
(-5510 3610);
DISPLAY 0.617021 (-5510 3610);
PAINT ORANGE (-5510 3610);
FORCEPROP 2 LASTPROP $XRERR UNIQUE?
J 0
(-5750 3610);
DISPLAY 0.638298 (-5750 3610);
PAINT MONO (-5750 3610);
DISPLAY INVISIBLE (-5750 3610);
WIRE 16 -1 (-3900 2675)(-2525 2675);
FORCEPROP 2 LAST SIG_NAME SP1_BMC_HOST_UART_TX
J 0
(-3810 2685);
DISPLAY 0.617021 (-3810 2685);
PAINT ORANGE (-3810 2685);
WIRE 16 -1 (-3900 2625)(-2525 2625);
FORCEPROP 2 LAST SIG_NAME UART_BMC_TXD5
J 0
(-3810 2635);
DISPLAY 0.617021 (-3810 2635);
PAINT ORANGE (-3810 2635);
WIRE 16 -1 (-4675 900)(-4025 900);
FORCEPROP 2 LAST SIG_NAME SPA_MID_DBG_RX
J 0
(-4585 910);
DISPLAY 0.680851 (-4585 910);
PAINT ORANGE (-4585 910);
WIRE 16 -1 (-4025 900)(-4025 1525);
WIRE 16 -1 (-4025 900)(-3725 900);
WIRE 16 -1 (-4025 1525)(-2750 1525);
WIRE 16 -1 (-3450 2025)(-1850 2025);
FORCEPROP 2 LAST SIG_NAME FM_UARTSW_LSB_N
J 0
(-3360 2035);
DISPLAY 0.617021 (-3360 2035);
PAINT ORANGE (-3360 2035);
WIRE 16 -1 (-1850 2475)(-1850 2025);
WIRE 16 -1 (-2025 2475)(-1850 2475);
WIRE 16 -1 (-850 2625)(-850 3450);
WIRE 16 -1 (-850 2625)(-650 2625);
WIRE 16 -1 (-1225 2625)(-850 2625);
FORCEPROP 2 LAST SIG_NAME SPA_MID_DBG_TX
J 0
(-1185 2635);
DISPLAY 0.617021 (-1185 2635);
PAINT ORANGE (-1185 2635);
WIRE 16 -1 (-850 3450)(-1800 3450);
WIRE 16 -1 (-4675 750)(-2900 750);
FORCEPROP 2 LAST SIG_NAME FM_UARTSW_LSB_N
J 0
(-4585 760);
DISPLAY 0.617021 (-4585 760);
PAINT ORANGE (-4585 760);
WIRE 16 -1 (-4675 800)(-2900 800);
FORCEPROP 2 LAST SIG_NAME FM_UARTSW_MSB_N
J 0
(-4585 810);
DISPLAY 0.617021 (-4585 810);
PAINT ORANGE (-4585 810);
WIRE 16 -1 (-3450 1975)(-1800 1975);
FORCEPROP 2 LAST SIG_NAME FM_UARTSW_MSB_N
J 0
(-3360 1985);
DISPLAY 0.617021 (-3360 1985);
PAINT ORANGE (-3360 1985);
WIRE 16 -1 (-1800 2525)(-1800 1975);
WIRE 16 -1 (-2025 2525)(-1800 2525);
WIRE 16 -1 (-3050 2575)(-2975 2575);
FORCEPROP 2 LAST SIG_NAME SP2_BMC_CM_UART_TX_R
J 0
(-3035 2585);
DISPLAY 0.617021 (-3035 2585);
PAINT ORANGE (-3035 2585);
FORCEPROP 2 LASTPROP $XRERR UNIQUE?
J 0
(-3275 2585);
DISPLAY 0.638298 (-3275 2585);
PAINT MONO (-3275 2585);
DISPLAY INVISIBLE (-3275 2585);
WIRE 16 -1 (-2975 2575)(-2975 3750);
WIRE 16 -1 (-2525 2575)(-2975 2575);
WIRE 16 -1 (-3025 3750)(-2975 3750);
WIRE 16 -1 (-2400 950)(-775 950);
FORCEPROP 2 LAST SIG_NAME SP1_BMC_HOST_UART_RX
J 2
(-785 960);
DISPLAY 0.617021 (-785 960);
PAINT ORANGE (-785 960);
WIRE 16 -1 (-2400 900)(-775 900);
FORCEPROP 2 LAST SIG_NAME UART_BMC_RXD5
J 2
(-800 910);
DISPLAY 0.617021 (-800 910);
PAINT ORANGE (-800 910);
WIRE 16 -1 (-1225 1525)(-1225 850);
WIRE 16 -1 (-1225 1525)(-2550 1525);
WIRE 16 -1 (-1225 850)(-775 850);
FORCEPROP 2 LAST SIG_NAME SP2_BMC_CM_UART_RX
J 2
(-800 860);
DISPLAY 0.617021 (-800 860);
PAINT ORANGE (-800 860);
WIRE 16 -1 (-1300 850)(-1225 850);
WIRE 16 -1 (-1525 850)(-1525 1775);
WIRE 16 -1 (-1500 850)(-1525 850);
WIRE 16 -1 (-1525 850)(-2400 850);
FORCEPROP 2 LAST SIG_NAME SP2_BMC_CM_UART_RX_R
J 0
(-2335 860);
DISPLAY 0.617021 (-2335 860);
PAINT ORANGE (-2335 860);
FORCEPROP 2 LASTPROP $XRERR UNIQUE?
J 0
(-2575 860);
DISPLAY 0.638298 (-2575 860);
PAINT MONO (-2575 860);
DISPLAY INVISIBLE (-2575 860);
WIRE 16 -1 (-1525 1775)(-1350 1775);
WIRE 16 -1 (-1150 1775)(-525 1775);
FORCEPROP 2 LAST SIG_NAME SP2_BMC_CM_UART_RX_R1
J 0
(-1110 1785);
DISPLAY 0.617021 (-1110 1785);
PAINT ORANGE (-1110 1785);
WIRE 16 -1 (-3525 900)(-2900 900);
FORCEPROP 2 LAST SIG_NAME UART_MUX_IN_R
J 0
(-3485 910);
DISPLAY 0.617021 (-3485 910);
PAINT ORANGE (-3485 910);
FORCEPROP 2 LASTPROP $XRERR UNIQUE?
J 0
(-3725 910);
DISPLAY 0.638298 (-3725 910);
PAINT MONO (-3725 910);
DISPLAY INVISIBLE (-3725 910);
WIRE 16 -1 (-3875 3750)(-3225 3750);
FORCEPROP 2 LAST SIG_NAME SP2_BMC_CM_UART_TX_R1
J 0
(-3835 3760);
DISPLAY 0.617021 (-3835 3760);
PAINT ORANGE (-3835 3760);
WIRE 16 -1 (-7050 3200)(-5825 3200);
FORCEPROP 2 LAST SIG_NAME FM_UARTSW_LSB_N
J 0
(-7010 3210);
DISPLAY 0.617021 (-7010 3210);
PAINT ORANGE (-7010 3210);
WIRE 16 -1 (-4975 3200)(-5625 3200);
FORCEPROP 2 LAST SIG_NAME FM_UARTSW_LSB_R_N
J 0
(-5510 3210);
DISPLAY 0.617021 (-5510 3210);
PAINT ORANGE (-5510 3210);
FORCEPROP 2 LASTPROP $XRERR UNIQUE?
J 0
(-5750 3210);
DISPLAY 0.638298 (-5750 3210);
PAINT MONO (-5750 3210);
DISPLAY INVISIBLE (-5750 3210);
WIRE 16 -1 (-2025 2625)(-1425 2625);
FORCEPROP 2 LAST SIG_NAME UART_MUX_OUT_R
J 2
(-1475 2635);
DISPLAY 0.617021 (-1475 2635);
PAINT ORANGE (-1475 2635);
FORCEPROP 2 LASTPROP $XRERR UNIQUE?
J 0
(-1715 2635);
DISPLAY 0.638298 (-1715 2635);
PAINT MONO (-1715 2635);
DISPLAY INVISIBLE (-1715 2635);
DOT 1 (-3225 4350);
DOT 1 (-3225 4775);
DOT 1 (-850 2625);
DOT 1 (-1525 850);
DOT 1 (-4400 3600);
DOT 1 (-4525 4675);
DOT 1 (-3100 1350);
DOT 1 (-3275 2575);
DOT 1 (-2975 2575);
DOT 1 (-1225 850);
DOT 1 (-1950 3075);
DOT 1 (-3850 4350);
DOT 1 (-3850 4775);
DOT 1 (-3225 4875);
DOT 1 (-2625 4350);
DOT 1 (-2625 4875);
DOT 1 (-1925 4350);
DOT 1 (-1925 4875);
DOT 1 (-50 4675);
DOT 1 (-4025 900);
DOT 1 (-4525 4775);
FORCENOTE
$CDS_IMAGE|19 Crescent City UART Mux Block Diagram rev1.1.jpg|3147|1500
(-6288 2150) 0;
DISPLAY CENTER (-6288 2150);
PAINT MONO (-6288 2150);
FORCENOTE
MIDPLANE/DEBUG CONNECTOR CONNECTED TO
(-1875 4700) 0;
DISPLAY LEFT (-1875 4700);
DISPLAY 1.021277 (-1875 4700);
PAINT PURPLE (-1875 4700);
FORCENOTE
UART1: HOST UART/EMS (IE/BMC)
(-1875 4600) 0;
DISPLAY LEFT (-1875 4600);
DISPLAY 1.021277 (-1875 4600);
PAINT PURPLE (-1875 4600);
FORCENOTE
UART5: DEBUG UART (IE/BMC)
(-1875 4525) 0;
DISPLAY LEFT (-1875 4525);
DISPLAY 1.021277 (-1875 4525);
PAINT PURPLE (-1875 4525);
FORCENOTE
UART2: IPMI OVER SERIAL (IE/BMC)
(-1875 4450) 0;
DISPLAY LEFT (-1875 4450);
DISPLAY 1.021277 (-1875 4450);
PAINT PURPLE (-1875 4450);
FORCENOTE
NO CONNECTION
(-1875 4375) 0;
DISPLAY LEFT (-1875 4375);
DISPLAY 1.021277 (-1875 4375);
PAINT PURPLE (-1875 4375);
FORCENOTE
ON
(-2300 4375) 0;
DISPLAY LEFT (-2300 4375);
DISPLAY 1.021277 (-2300 4375);
PAINT PURPLE (-2300 4375);
FORCENOTE
BOM_COST=DEBUG
(-7750 200) 0;
DISPLAY LEFT (-7750 200);
DISPLAY 1.595745 (-7750 200);
PAINT PURPLE (-7750 200);
FORCENOTE
ROOM=UART_MUX
(-7750 325) 0;
DISPLAY LEFT (-7750 325);
DISPLAY 1.595745 (-7750 325);
PAINT PURPLE (-7750 325);
FORCENOTE
0
(-4250 4375) 0;
DISPLAY LEFT (-4250 4375);
DISPLAY 1.021277 (-4250 4375);
PAINT PURPLE (-4250 4375);
FORCENOTE
1
(-4250 4600) 0;
DISPLAY LEFT (-4250 4600);
DISPLAY 1.021277 (-4250 4600);
PAINT PURPLE (-4250 4600);
FORCENOTE
0
(-3600 4525) 0;
DISPLAY LEFT (-3600 4525);
DISPLAY 1.021277 (-3600 4525);
PAINT PURPLE (-3600 4525);
FORCENOTE
1
(-3600 4450) 0;
DISPLAY LEFT (-3600 4450);
DISPLAY 1.021277 (-3600 4450);
PAINT PURPLE (-3600 4450);
FORCENOTE
0
(-3600 4375) 0;
DISPLAY LEFT (-3600 4375);
DISPLAY 1.021277 (-3600 4375);
PAINT PURPLE (-3600 4375);
FORCENOTE
FM_UARTSW_MSB_N
(-3150 4700) 0;
DISPLAY LEFT (-3150 4700);
DISPLAY 0.808511 (-3150 4700);
PAINT PURPLE (-3150 4700);
FORCENOTE
MSB GREEN
(-3100 4800) 0;
DISPLAY LEFT (-3100 4800);
DISPLAY 1.021277 (-3100 4800);
PAINT PURPLE (-3100 4800);
FORCENOTE
OFF
(-2950 4525) 0;
DISPLAY LEFT (-2950 4525);
DISPLAY 1.021277 (-2950 4525);
PAINT PURPLE (-2950 4525);
FORCENOTE
OFF
(-2950 4600) 0;
DISPLAY LEFT (-2950 4600);
DISPLAY 1.021277 (-2950 4600);
PAINT PURPLE (-2950 4600);
FORCENOTE
OFF
(-2300 4450) 0;
DISPLAY LEFT (-2300 4450);
DISPLAY 1.021277 (-2300 4450);
PAINT PURPLE (-2300 4450);
FORCENOTE
ON
(-2300 4525) 0;
DISPLAY LEFT (-2300 4525);
DISPLAY 1.021277 (-2300 4525);
PAINT PURPLE (-2300 4525);
FORCENOTE
OFF
(-2300 4600) 0;
DISPLAY LEFT (-2300 4600);
DISPLAY 1.021277 (-2300 4600);
PAINT PURPLE (-2300 4600);
FORCENOTE
FM_UARTSW_LSB_N
(-2500 4700) 0;
DISPLAY LEFT (-2500 4700);
DISPLAY 0.808511 (-2500 4700);
PAINT PURPLE (-2500 4700);
FORCENOTE
LSB GREEN
(-2425 4800) 0;
DISPLAY LEFT (-2425 4800);
DISPLAY 1.021277 (-2425 4800);
PAINT PURPLE (-2425 4800);
FORCENOTE
. 
(50 50) 0;
DISPLAY LEFT (50 50);
DISPLAY 0.617021 (50 50);
PAINT PURPLE (50 50);
FORCENOTE
ON
(-2950 4375) 0;
DISPLAY LEFT (-2950 4375);
DISPLAY 1.021277 (-2950 4375);
PAINT PURPLE (-2950 4375);
FORCENOTE
1
(-3600 4600) 0;
DISPLAY LEFT (-3600 4600);
DISPLAY 1.021277 (-3600 4600);
PAINT PURPLE (-3600 4600);
FORCENOTE
FM_UARTSW_LSB_N
(-3800 4700) 0;
DISPLAY LEFT (-3800 4700);
DISPLAY 0.808511 (-3800 4700);
PAINT PURPLE (-3800 4700);
FORCENOTE
CPLD MAPPING
(-4100 4800) 0;
DISPLAY LEFT (-4100 4800);
DISPLAY 1.021277 (-4100 4800);
PAINT PURPLE (-4100 4800);
FORCENOTE
ON
(-2950 4450) 0;
DISPLAY LEFT (-2950 4450);
DISPLAY 1.021277 (-2950 4450);
PAINT PURPLE (-2950 4450);
FORCENOTE
FM_UARTSW_MSB_N
(-4450 4700) 0;
DISPLAY LEFT (-4450 4700);
DISPLAY 0.808511 (-4450 4700);
PAINT PURPLE (-4450 4700);
FORCENOTE
0
(-4250 4450) 0;
DISPLAY LEFT (-4250 4450);
DISPLAY 1.021277 (-4250 4450);
PAINT PURPLE (-4250 4450);
FORCENOTE
1
(-4250 4525) 0;
DISPLAY LEFT (-4250 4525);
DISPLAY 1.021277 (-4250 4525);
PAINT PURPLE (-4250 4525);
FORCENOTE
FROM MIDPLANE CONN A
(-4300 3650) 0;
DISPLAY LEFT (-4300 3650);
DISPLAY 1.021277 (-4300 3650);
PAINT PURPLE (-4300 3650);
FORCENOTE
TO MIDPLANE CONN A
(-1100 1625) 0;
DISPLAY LEFT (-1100 1625);
DISPLAY 1.021277 (-1100 1625);
PAINT PURPLE (-1100 1625);
FORCENOTE
TP FAB1 POP R9F65
(-4175 3075) 0;
DISPLAY LEFT (-4175 3075);
DISPLAY 1.021277 (-4175 3075);
PAINT RED (-4175 3075);
FORCENOTE
NOPOP R9F66 1123
(-3925 3000) 0;
DISPLAY LEFT (-3925 3000);
DISPLAY 1.021277 (-3925 3000);
PAINT RED (-3925 3000);
FORCENOTE
NOPOP R9F68 1123
(-750 525) 0;
DISPLAY LEFT (-750 525);
DISPLAY 1.021277 (-750 525);
PAINT RED (-750 525);
FORCENOTE
TP FAB1 POP R9F69
(-975 575) 0;
DISPLAY LEFT (-975 575);
DISPLAY 1.021277 (-975 575);
PAINT RED (-975 575);
QUIT
